FILE_TYPE = MACRO_DRAWING;
SET COLOR_WIRE YELLOW;
SET COLOR_PROP ORANGE;
SET COLOR_DOT WHITE;
SET COLOR_ARC YELLOW;
SET COLOR_BODY GREEN;
SET COLOR_NOTE PURPLE;
SET PROP_DISPLAY VALUE;
SET PAGE_NUMBER P114;
FORCEADD OFFPAGE..1
(-10450 4575);
FORCEPROP 2 LAST $XR0 97 
J 0
(-10701 4575);
DISPLAY 0.638298 (-10701 4575);
PAINT MONO (-10701 4575);
FORCEPROP 2 LAST CDS_LIB standard
J 0
(-10450 4575);
PAINT MONO (-10450 4575);
DISPLAY INVISIBLE (-10450 4575);
FORCEPROP 1 LAST OFFPAGE TRUE
J 0
(-10125 4450);
DISPLAY 0.872340 (-10125 4450);
PAINT GREEN (-10125 4450);
DISPLAY INVISIBLE (-10125 4450);
FORCEPROP 1 LAST COMMENT_BODY TRUE
J 0
(-10325 4475);
DISPLAY 0.872340 (-10325 4475);
PAINT GREEN (-10325 4475);
DISPLAY INVISIBLE (-10325 4475);
FORCEPROP 2 LAST PATH I1
J 0
(-10650 4625);
DISPLAY 1.021277 (-10650 4625);
DISPLAY INVISIBLE (-10650 4625);
FORCEADD OFFPAGE..1
(-10450 5725);
FORCEPROP 2 LAST $XR0 88 
J 0
(-10701 5725);
DISPLAY 0.638298 (-10701 5725);
PAINT MONO (-10701 5725);
FORCEPROP 2 LAST CDS_LIB standard
J 0
(-10450 5725);
PAINT MONO (-10450 5725);
DISPLAY INVISIBLE (-10450 5725);
FORCEPROP 1 LAST OFFPAGE TRUE
J 0
(-10125 5600);
DISPLAY 0.872340 (-10125 5600);
PAINT GREEN (-10125 5600);
DISPLAY INVISIBLE (-10125 5600);
FORCEPROP 1 LAST COMMENT_BODY TRUE
J 0
(-10325 5625);
DISPLAY 0.872340 (-10325 5625);
PAINT GREEN (-10325 5625);
DISPLAY INVISIBLE (-10325 5625);
FORCEPROP 2 LAST PATH I10
J 0
(-10650 5775);
DISPLAY 1.021277 (-10650 5775);
DISPLAY INVISIBLE (-10650 5775);
FORCEADD OFFPAGE..1
(-10450 5950);
FORCEPROP 2 LAST $XR0 86 
J 0
(-10701 5950);
DISPLAY 0.638298 (-10701 5950);
PAINT MONO (-10701 5950);
FORCEPROP 2 LAST CDS_LIB standard
J 0
(-10450 5950);
PAINT MONO (-10450 5950);
DISPLAY INVISIBLE (-10450 5950);
FORCEPROP 1 LAST OFFPAGE TRUE
J 0
(-10125 5825);
DISPLAY 0.872340 (-10125 5825);
PAINT GREEN (-10125 5825);
DISPLAY INVISIBLE (-10125 5825);
FORCEPROP 1 LAST COMMENT_BODY TRUE
J 0
(-10325 5850);
DISPLAY 0.872340 (-10325 5850);
PAINT GREEN (-10325 5850);
DISPLAY INVISIBLE (-10325 5850);
FORCEPROP 2 LAST PATH I11
J 0
(-10650 6000);
DISPLAY 1.021277 (-10650 6000);
DISPLAY INVISIBLE (-10650 6000);
FORCEADD OFFPAGE..1
(-10450 5900);
FORCEPROP 2 LAST $XR0 87 
J 0
(-10701 5900);
DISPLAY 0.638298 (-10701 5900);
PAINT MONO (-10701 5900);
FORCEPROP 2 LAST CDS_LIB standard
J 0
(-10450 5900);
PAINT MONO (-10450 5900);
DISPLAY INVISIBLE (-10450 5900);
FORCEPROP 1 LAST OFFPAGE TRUE
J 0
(-10125 5775);
DISPLAY 0.872340 (-10125 5775);
PAINT GREEN (-10125 5775);
DISPLAY INVISIBLE (-10125 5775);
FORCEPROP 1 LAST COMMENT_BODY TRUE
J 0
(-10325 5800);
DISPLAY 0.872340 (-10325 5800);
PAINT GREEN (-10325 5800);
DISPLAY INVISIBLE (-10325 5800);
FORCEPROP 2 LAST PATH I12
J 0
(-10650 5950);
DISPLAY 1.021277 (-10650 5950);
DISPLAY INVISIBLE (-10650 5950);
FORCEADD OFFPAGE..1
(-10450 6275);
FORCEPROP 2 LAST $XR0 84 
J 0
(-10701 6275);
DISPLAY 0.638298 (-10701 6275);
PAINT MONO (-10701 6275);
FORCEPROP 2 LAST CDS_LIB standard
J 0
(-10450 6275);
PAINT MONO (-10450 6275);
DISPLAY INVISIBLE (-10450 6275);
FORCEPROP 1 LAST OFFPAGE TRUE
J 0
(-10125 6150);
DISPLAY 0.872340 (-10125 6150);
PAINT GREEN (-10125 6150);
DISPLAY INVISIBLE (-10125 6150);
FORCEPROP 1 LAST COMMENT_BODY TRUE
J 0
(-10325 6175);
DISPLAY 0.872340 (-10325 6175);
PAINT GREEN (-10325 6175);
DISPLAY INVISIBLE (-10325 6175);
FORCEPROP 2 LAST PATH I13
J 0
(-10650 6325);
DISPLAY 1.021277 (-10650 6325);
DISPLAY INVISIBLE (-10650 6325);
FORCEADD OFFPAGE..1
(-10450 6225);
FORCEPROP 2 LAST $XR0 85 
J 0
(-10701 6225);
DISPLAY 0.638298 (-10701 6225);
PAINT MONO (-10701 6225);
FORCEPROP 2 LAST CDS_LIB standard
J 0
(-10450 6225);
PAINT MONO (-10450 6225);
DISPLAY INVISIBLE (-10450 6225);
FORCEPROP 1 LAST OFFPAGE TRUE
J 0
(-10125 6100);
DISPLAY 0.872340 (-10125 6100);
PAINT GREEN (-10125 6100);
DISPLAY INVISIBLE (-10125 6100);
FORCEPROP 1 LAST COMMENT_BODY TRUE
J 0
(-10325 6125);
DISPLAY 0.872340 (-10325 6125);
PAINT GREEN (-10325 6125);
DISPLAY INVISIBLE (-10325 6125);
FORCEPROP 2 LAST PATH I14
J 0
(-10650 6275);
DISPLAY 1.021277 (-10650 6275);
DISPLAY INVISIBLE (-10650 6275);
FORCEADD OFFPAGE..1
(-10450 6450);
FORCEPROP 2 LAST $XR0 83 
J 0
(-10701 6450);
DISPLAY 0.638298 (-10701 6450);
PAINT MONO (-10701 6450);
FORCEPROP 2 LAST CDS_LIB standard
J 0
(-10450 6450);
PAINT MONO (-10450 6450);
DISPLAY INVISIBLE (-10450 6450);
FORCEPROP 1 LAST OFFPAGE TRUE
J 0
(-10125 6325);
DISPLAY 0.872340 (-10125 6325);
PAINT GREEN (-10125 6325);
DISPLAY INVISIBLE (-10125 6325);
FORCEPROP 1 LAST COMMENT_BODY TRUE
J 0
(-10325 6350);
DISPLAY 0.872340 (-10325 6350);
PAINT GREEN (-10325 6350);
DISPLAY INVISIBLE (-10325 6350);
FORCEPROP 2 LAST PATH I15
J 0
(-10650 6500);
DISPLAY 1.021277 (-10650 6500);
DISPLAY INVISIBLE (-10650 6500);
FORCEADD OFFPAGE..1
(-10450 6500);
FORCEPROP 2 LAST $XR0 82 
J 0
(-10701 6500);
DISPLAY 0.638298 (-10701 6500);
PAINT MONO (-10701 6500);
FORCEPROP 2 LAST CDS_LIB standard
J 0
(-10450 6500);
PAINT MONO (-10450 6500);
DISPLAY INVISIBLE (-10450 6500);
FORCEPROP 1 LAST OFFPAGE TRUE
J 0
(-10125 6375);
DISPLAY 0.872340 (-10125 6375);
PAINT GREEN (-10125 6375);
DISPLAY INVISIBLE (-10125 6375);
FORCEPROP 1 LAST COMMENT_BODY TRUE
J 0
(-10325 6400);
DISPLAY 0.872340 (-10325 6400);
PAINT GREEN (-10325 6400);
DISPLAY INVISIBLE (-10325 6400);
FORCEPROP 2 LAST PATH I16
J 0
(-10650 6550);
DISPLAY 1.021277 (-10650 6550);
DISPLAY INVISIBLE (-10650 6550);
FORCEADD Q_RES..1
(-9375 4575);
FORCEPROP 1 LAST PART_NUMBER CS03322FB03
J 0
(-9475 4650);
DISPLAY 0.404255 (-9475 4650);
DISPLAY INVISIBLE (-9475 4650);
FORCEPROP 1 LAST TOLERANCE 1%
J 0
(-9150 4575);
DISPLAY 0.510638 (-9150 4575);
FORCEPROP 1 LAST VALUE 33.2
J 2
(-9175 4575);
DISPLAY 0.510638 (-9175 4575);
FORCEPROP 1 LAST $LOCATION R2735
J 0
(-9575 4575);
DISPLAY 0.638298 (-9575 4575);
FORCEPROP 1 LASTPIN (-9475 4575) $PN 1
J 0
(-9463 4587);
DISPLAY 0.787234 (-9463 4587);
FORCEPROP 1 LASTPIN (-9275 4575) $PN 2
J 0
(-9313 4587);
DISPLAY 0.787234 (-9313 4587);
FORCEPROP 1 LAST WATTAGE 1/16W
J 2
(-9150 4675);
DISPLAY 0.404255 (-9150 4675);
DISPLAY INVISIBLE (-9150 4675);
FORCEPROP 1 LAST PACK_TYPE 0402LF
J 0
(-9375 4675);
DISPLAY 0.404255 (-9375 4675);
DISPLAY INVISIBLE (-9375 4675);
FORCEPROP 1 LAST MATERIAL CHIP
J 0
(-9475 4675);
DISPLAY 0.404255 (-9475 4675);
DISPLAY INVISIBLE (-9475 4675);
FORCEPROP 2 LAST CDS_LIB pure_quanta
J 0
(-9375 4575);
PAINT MONO (-9375 4575);
DISPLAY INVISIBLE (-9375 4575);
FORCEPROP 1 LAST PATH I17
J 0
(-9425 4725);
DISPLAY 0.978723 (-9425 4725);
PAINT WHITE (-9425 4725);
DISPLAY INVISIBLE (-9425 4725);
FORCEPROP 2 LAST CDS_LOCATION R2735
J 0
(-9425 4775);
DISPLAY 1.021277 (-9425 4775);
DISPLAY INVISIBLE (-9425 4775);
FORCEPROP 2 LAST $SEC 1
J 0
(-9425 4775);
DISPLAY 0.680851 (-9425 4775);
PAINT MONO (-9425 4775);
DISPLAY INVISIBLE (-9425 4775);
FORCEPROP 2 LAST CDS_SEC 1
J 0
(-9425 4775);
DISPLAY 1.021277 (-9425 4775);
DISPLAY INVISIBLE (-9425 4775);
FORCEADD Q_RES..1
(-9375 4625);
FORCEPROP 1 LAST PART_NUMBER CS03322FB03
J 0
(-9475 4700);
DISPLAY 0.404255 (-9475 4700);
DISPLAY INVISIBLE (-9475 4700);
FORCEPROP 1 LAST WATTAGE 1/16W
J 2
(-9150 4725);
DISPLAY 0.404255 (-9150 4725);
FORCEPROP 1 LAST TOLERANCE 1%
J 0
(-9150 4625);
DISPLAY 0.510638 (-9150 4625);
FORCEPROP 1 LAST VALUE 33.2
J 2
(-9175 4625);
DISPLAY 0.510638 (-9175 4625);
FORCEPROP 1 LAST MATERIAL CHIP
J 0
(-9475 4725);
DISPLAY 0.404255 (-9475 4725);
FORCEPROP 1 LAST PACK_TYPE 0402LF
J 0
(-9375 4725);
DISPLAY 0.404255 (-9375 4725);
FORCEPROP 1 LAST $LOCATION R2734
J 0
(-9575 4625);
DISPLAY 0.638298 (-9575 4625);
FORCEPROP 1 LASTPIN (-9475 4625) $PN 1
J 0
(-9463 4637);
DISPLAY 0.787234 (-9463 4637);
FORCEPROP 1 LASTPIN (-9275 4625) $PN 2
J 0
(-9313 4637);
DISPLAY 0.787234 (-9313 4637);
FORCEPROP 2 LAST CDS_LIB pure_quanta
J 0
(-9375 4625);
PAINT MONO (-9375 4625);
DISPLAY INVISIBLE (-9375 4625);
FORCEPROP 1 LAST PATH I18
J 0
(-9425 4775);
DISPLAY 0.978723 (-9425 4775);
PAINT WHITE (-9425 4775);
DISPLAY INVISIBLE (-9425 4775);
FORCEPROP 2 LAST CDS_LOCATION R2734
J 0
(-9425 4825);
DISPLAY 1.021277 (-9425 4825);
DISPLAY INVISIBLE (-9425 4825);
FORCEPROP 2 LAST $SEC 1
J 0
(-9425 4825);
DISPLAY 0.680851 (-9425 4825);
PAINT MONO (-9425 4825);
DISPLAY INVISIBLE (-9425 4825);
FORCEPROP 2 LAST CDS_SEC 1
J 0
(-9425 4825);
DISPLAY 1.021277 (-9425 4825);
DISPLAY INVISIBLE (-9425 4825);
FORCEADD Q_RES..1
(-9375 4800);
FORCEPROP 1 LAST PART_NUMBER CS03322FB03
J 0
(-9475 4875);
DISPLAY 0.404255 (-9475 4875);
DISPLAY INVISIBLE (-9475 4875);
FORCEPROP 1 LAST TOLERANCE 1%
J 0
(-9150 4800);
DISPLAY 0.510638 (-9150 4800);
FORCEPROP 1 LAST VALUE 33.2
J 2
(-9175 4800);
DISPLAY 0.510638 (-9175 4800);
FORCEPROP 1 LAST $LOCATION R890
J 0
(-9575 4800);
DISPLAY 0.638298 (-9575 4800);
FORCEPROP 1 LASTPIN (-9475 4800) $PN 1
J 0
(-9463 4812);
DISPLAY 0.787234 (-9463 4812);
FORCEPROP 1 LASTPIN (-9275 4800) $PN 2
J 0
(-9313 4812);
DISPLAY 0.787234 (-9313 4812);
FORCEPROP 1 LAST WATTAGE 1/16W
J 2
(-9150 4900);
DISPLAY 0.404255 (-9150 4900);
DISPLAY INVISIBLE (-9150 4900);
FORCEPROP 1 LAST PACK_TYPE 0402LF
J 0
(-9375 4900);
DISPLAY 0.404255 (-9375 4900);
DISPLAY INVISIBLE (-9375 4900);
FORCEPROP 1 LAST MATERIAL CHIP
J 0
(-9475 4900);
DISPLAY 0.404255 (-9475 4900);
DISPLAY INVISIBLE (-9475 4900);
FORCEPROP 2 LAST CDS_LIB pure_quanta
J 0
(-9375 4800);
PAINT MONO (-9375 4800);
DISPLAY INVISIBLE (-9375 4800);
FORCEPROP 1 LAST PATH I19
J 0
(-9425 4950);
DISPLAY 0.978723 (-9425 4950);
PAINT WHITE (-9425 4950);
DISPLAY INVISIBLE (-9425 4950);
FORCEPROP 1 LAST $LOCATION R890
J 0
(-9425 5000);
DISPLAY 1.021277 (-9425 5000);
DISPLAY INVISIBLE (-9425 5000);
FORCEPROP 2 LAST CDS_LOCATION R890
J 0
(-9425 5000);
DISPLAY 1.021277 (-9425 5000);
DISPLAY INVISIBLE (-9425 5000);
FORCEPROP 2 LAST $SEC 1
J 0
(-9425 5000);
DISPLAY 0.680851 (-9425 5000);
PAINT MONO (-9425 5000);
DISPLAY INVISIBLE (-9425 5000);
FORCEPROP 2 LAST CDS_SEC 1
J 0
(-9425 5000);
DISPLAY 1.021277 (-9425 5000);
DISPLAY INVISIBLE (-9425 5000);
FORCEADD OFFPAGE..1
(-10450 4625);
FORCEPROP 2 LAST $XR0 96 
J 0
(-10701 4625);
DISPLAY 0.638298 (-10701 4625);
PAINT MONO (-10701 4625);
FORCEPROP 2 LAST CDS_LIB standard
J 0
(-10450 4625);
PAINT MONO (-10450 4625);
DISPLAY INVISIBLE (-10450 4625);
FORCEPROP 1 LAST OFFPAGE TRUE
J 0
(-10125 4500);
DISPLAY 0.872340 (-10125 4500);
PAINT GREEN (-10125 4500);
DISPLAY INVISIBLE (-10125 4500);
FORCEPROP 1 LAST COMMENT_BODY TRUE
J 0
(-10325 4525);
DISPLAY 0.872340 (-10325 4525);
PAINT GREEN (-10325 4525);
DISPLAY INVISIBLE (-10325 4525);
FORCEPROP 2 LAST PATH I2
J 0
(-10650 4675);
DISPLAY 1.021277 (-10650 4675);
DISPLAY INVISIBLE (-10650 4675);
FORCEADD Q_RES..1
(-9375 4850);
FORCEPROP 1 LAST PART_NUMBER CS03322FB03
J 0
(-9475 4925);
DISPLAY 0.404255 (-9475 4925);
DISPLAY INVISIBLE (-9475 4925);
FORCEPROP 1 LAST TOLERANCE 1%
J 0
(-9150 4850);
DISPLAY 0.510638 (-9150 4850);
FORCEPROP 1 LAST VALUE 33.2
J 2
(-9175 4850);
DISPLAY 0.510638 (-9175 4850);
FORCEPROP 1 LAST MATERIAL CHIP
J 0
(-9475 4950);
DISPLAY 0.404255 (-9475 4950);
FORCEPROP 1 LAST WATTAGE 1/16W
J 2
(-9150 4950);
DISPLAY 0.404255 (-9150 4950);
FORCEPROP 1 LAST PACK_TYPE 0402LF
J 0
(-9375 4950);
DISPLAY 0.404255 (-9375 4950);
FORCEPROP 1 LAST $LOCATION R889
J 0
(-9575 4850);
DISPLAY 0.638298 (-9575 4850);
FORCEPROP 1 LASTPIN (-9475 4850) $PN 1
J 0
(-9463 4862);
DISPLAY 0.787234 (-9463 4862);
FORCEPROP 1 LASTPIN (-9275 4850) $PN 2
J 0
(-9313 4862);
DISPLAY 0.787234 (-9313 4862);
FORCEPROP 2 LAST CDS_LIB pure_quanta
J 0
(-9375 4850);
PAINT MONO (-9375 4850);
DISPLAY INVISIBLE (-9375 4850);
FORCEPROP 1 LAST PATH I20
J 0
(-9425 5000);
DISPLAY 0.978723 (-9425 5000);
PAINT WHITE (-9425 5000);
DISPLAY INVISIBLE (-9425 5000);
FORCEPROP 1 LAST $LOCATION R889
J 0
(-9425 5050);
DISPLAY 1.021277 (-9425 5050);
DISPLAY INVISIBLE (-9425 5050);
FORCEPROP 2 LAST CDS_LOCATION R889
J 0
(-9425 5050);
DISPLAY 1.021277 (-9425 5050);
DISPLAY INVISIBLE (-9425 5050);
FORCEPROP 2 LAST $SEC 1
J 0
(-9425 5050);
DISPLAY 0.680851 (-9425 5050);
PAINT MONO (-9425 5050);
DISPLAY INVISIBLE (-9425 5050);
FORCEPROP 2 LAST CDS_SEC 1
J 0
(-9425 5050);
DISPLAY 1.021277 (-9425 5050);
DISPLAY INVISIBLE (-9425 5050);
FORCEADD Q_RES..1
(-9375 5125);
FORCEPROP 1 LAST PART_NUMBER CS03322FB03
J 0
(-9475 5200);
DISPLAY 0.404255 (-9475 5200);
DISPLAY INVISIBLE (-9475 5200);
FORCEPROP 1 LAST VALUE 33.2
J 2
(-9175 5125);
DISPLAY 0.510638 (-9175 5125);
FORCEPROP 1 LAST TOLERANCE 1%
J 0
(-9150 5125);
DISPLAY 0.510638 (-9150 5125);
FORCEPROP 1 LAST $LOCATION R2733
J 0
(-9575 5125);
DISPLAY 0.638298 (-9575 5125);
FORCEPROP 1 LASTPIN (-9475 5125) $PN 1
J 0
(-9463 5137);
DISPLAY 0.787234 (-9463 5137);
FORCEPROP 1 LASTPIN (-9275 5125) $PN 2
J 0
(-9313 5137);
DISPLAY 0.787234 (-9313 5137);
FORCEPROP 1 LAST WATTAGE 1/16W
J 2
(-9150 5225);
DISPLAY 0.404255 (-9150 5225);
DISPLAY INVISIBLE (-9150 5225);
FORCEPROP 1 LAST PACK_TYPE 0402LF
J 0
(-9375 5225);
DISPLAY 0.404255 (-9375 5225);
DISPLAY INVISIBLE (-9375 5225);
FORCEPROP 1 LAST MATERIAL CHIP
J 0
(-9475 5225);
DISPLAY 0.404255 (-9475 5225);
DISPLAY INVISIBLE (-9475 5225);
FORCEPROP 2 LAST CDS_LIB pure_quanta
J 0
(-9375 5125);
PAINT MONO (-9375 5125);
DISPLAY INVISIBLE (-9375 5125);
FORCEPROP 1 LAST PATH I21
J 0
(-9425 5275);
DISPLAY 0.978723 (-9425 5275);
PAINT WHITE (-9425 5275);
DISPLAY INVISIBLE (-9425 5275);
FORCEPROP 2 LAST CDS_LOCATION R2733
J 0
(-9425 5325);
DISPLAY 1.021277 (-9425 5325);
DISPLAY INVISIBLE (-9425 5325);
FORCEPROP 2 LAST $SEC 1
J 0
(-9425 5325);
DISPLAY 0.680851 (-9425 5325);
PAINT MONO (-9425 5325);
DISPLAY INVISIBLE (-9425 5325);
FORCEPROP 2 LAST CDS_SEC 1
J 0
(-9425 5325);
DISPLAY 1.021277 (-9425 5325);
DISPLAY INVISIBLE (-9425 5325);
FORCEADD Q_RES..1
(-9375 5175);
FORCEPROP 1 LAST PART_NUMBER CS03322FB03
J 0
(-9475 5250);
DISPLAY 0.404255 (-9475 5250);
DISPLAY INVISIBLE (-9475 5250);
FORCEPROP 1 LAST VALUE 33.2
J 2
(-9175 5175);
DISPLAY 0.510638 (-9175 5175);
FORCEPROP 1 LAST WATTAGE 1/16W
J 2
(-9175 5275);
DISPLAY 0.404255 (-9175 5275);
FORCEPROP 1 LAST MATERIAL CHIP
J 0
(-9475 5275);
DISPLAY 0.404255 (-9475 5275);
FORCEPROP 1 LAST PACK_TYPE 0402LF
J 0
(-9375 5275);
DISPLAY 0.404255 (-9375 5275);
FORCEPROP 1 LAST TOLERANCE 1%
J 0
(-9150 5175);
DISPLAY 0.510638 (-9150 5175);
FORCEPROP 1 LAST $LOCATION R2732
J 0
(-9575 5175);
DISPLAY 0.638298 (-9575 5175);
FORCEPROP 1 LASTPIN (-9475 5175) $PN 1
J 0
(-9463 5187);
DISPLAY 0.787234 (-9463 5187);
FORCEPROP 1 LASTPIN (-9275 5175) $PN 2
J 0
(-9313 5187);
DISPLAY 0.787234 (-9313 5187);
FORCEPROP 2 LAST CDS_LIB pure_quanta
J 0
(-9375 5175);
PAINT MONO (-9375 5175);
DISPLAY INVISIBLE (-9375 5175);
FORCEPROP 1 LAST PATH I22
J 0
(-9425 5325);
DISPLAY 0.978723 (-9425 5325);
PAINT WHITE (-9425 5325);
DISPLAY INVISIBLE (-9425 5325);
FORCEPROP 2 LAST CDS_LOCATION R2732
J 0
(-9425 5375);
DISPLAY 1.021277 (-9425 5375);
DISPLAY INVISIBLE (-9425 5375);
FORCEPROP 2 LAST $SEC 1
J 0
(-9425 5375);
DISPLAY 0.680851 (-9425 5375);
PAINT MONO (-9425 5375);
DISPLAY INVISIBLE (-9425 5375);
FORCEPROP 2 LAST CDS_SEC 1
J 0
(-9425 5375);
DISPLAY 1.021277 (-9425 5375);
DISPLAY INVISIBLE (-9425 5375);
FORCEADD Q_RES..1
(-9375 5350);
FORCEPROP 1 LAST PART_NUMBER CS03322FB03
J 0
(-9475 5425);
DISPLAY 0.404255 (-9475 5425);
DISPLAY INVISIBLE (-9475 5425);
FORCEPROP 1 LAST VALUE 33.2
J 2
(-9175 5350);
DISPLAY 0.510638 (-9175 5350);
FORCEPROP 1 LAST TOLERANCE 1%
J 0
(-9150 5350);
DISPLAY 0.510638 (-9150 5350);
FORCEPROP 1 LAST $LOCATION R886
J 0
(-9575 5350);
DISPLAY 0.638298 (-9575 5350);
FORCEPROP 1 LASTPIN (-9475 5350) $PN 1
J 0
(-9463 5362);
DISPLAY 0.787234 (-9463 5362);
FORCEPROP 1 LASTPIN (-9275 5350) $PN 2
J 0
(-9313 5362);
DISPLAY 0.787234 (-9313 5362);
FORCEPROP 1 LAST WATTAGE 1/16W
J 2
(-9150 5450);
DISPLAY 0.404255 (-9150 5450);
DISPLAY INVISIBLE (-9150 5450);
FORCEPROP 1 LAST PACK_TYPE 0402LF
J 0
(-9375 5450);
DISPLAY 0.404255 (-9375 5450);
DISPLAY INVISIBLE (-9375 5450);
FORCEPROP 1 LAST MATERIAL CHIP
J 0
(-9475 5450);
DISPLAY 0.404255 (-9475 5450);
DISPLAY INVISIBLE (-9475 5450);
FORCEPROP 2 LAST CDS_LIB pure_quanta
J 0
(-9375 5350);
PAINT MONO (-9375 5350);
DISPLAY INVISIBLE (-9375 5350);
FORCEPROP 1 LAST PATH I23
J 0
(-9425 5500);
DISPLAY 0.978723 (-9425 5500);
PAINT WHITE (-9425 5500);
DISPLAY INVISIBLE (-9425 5500);
FORCEPROP 1 LAST $LOCATION R886
J 0
(-9425 5550);
DISPLAY 1.021277 (-9425 5550);
DISPLAY INVISIBLE (-9425 5550);
FORCEPROP 2 LAST CDS_LOCATION R886
J 0
(-9425 5550);
DISPLAY 1.021277 (-9425 5550);
DISPLAY INVISIBLE (-9425 5550);
FORCEPROP 2 LAST $SEC 1
J 0
(-9425 5550);
DISPLAY 0.680851 (-9425 5550);
PAINT MONO (-9425 5550);
DISPLAY INVISIBLE (-9425 5550);
FORCEPROP 2 LAST CDS_SEC 1
J 0
(-9425 5550);
DISPLAY 1.021277 (-9425 5550);
DISPLAY INVISIBLE (-9425 5550);
FORCEADD Q_RES..1
(-9375 5400);
FORCEPROP 1 LAST PART_NUMBER CS03322FB03
J 0
(-9475 5475);
DISPLAY 0.404255 (-9475 5475);
DISPLAY INVISIBLE (-9475 5475);
FORCEPROP 1 LAST VALUE 33.2
J 2
(-9175 5400);
DISPLAY 0.510638 (-9175 5400);
FORCEPROP 1 LAST TOLERANCE 1%
J 0
(-9150 5400);
DISPLAY 0.510638 (-9150 5400);
FORCEPROP 1 LAST MATERIAL CHIP
J 0
(-9475 5500);
DISPLAY 0.404255 (-9475 5500);
FORCEPROP 1 LAST PACK_TYPE 0402LF
J 0
(-9375 5500);
DISPLAY 0.404255 (-9375 5500);
FORCEPROP 1 LAST WATTAGE 1/16W
J 2
(-9150 5500);
DISPLAY 0.404255 (-9150 5500);
FORCEPROP 1 LAST $LOCATION R885
J 0
(-9575 5400);
DISPLAY 0.638298 (-9575 5400);
FORCEPROP 1 LASTPIN (-9475 5400) $PN 1
J 0
(-9463 5412);
DISPLAY 0.787234 (-9463 5412);
FORCEPROP 1 LASTPIN (-9275 5400) $PN 2
J 0
(-9313 5412);
DISPLAY 0.787234 (-9313 5412);
FORCEPROP 2 LAST CDS_LIB pure_quanta
J 0
(-9375 5400);
PAINT MONO (-9375 5400);
DISPLAY INVISIBLE (-9375 5400);
FORCEPROP 1 LAST PATH I24
J 0
(-9425 5550);
DISPLAY 0.978723 (-9425 5550);
PAINT WHITE (-9425 5550);
DISPLAY INVISIBLE (-9425 5550);
FORCEPROP 1 LAST $LOCATION R885
J 0
(-9425 5600);
DISPLAY 1.021277 (-9425 5600);
DISPLAY INVISIBLE (-9425 5600);
FORCEPROP 2 LAST CDS_LOCATION R885
J 0
(-9425 5600);
DISPLAY 1.021277 (-9425 5600);
DISPLAY INVISIBLE (-9425 5600);
FORCEPROP 2 LAST $SEC 1
J 0
(-9425 5600);
DISPLAY 0.680851 (-9425 5600);
PAINT MONO (-9425 5600);
DISPLAY INVISIBLE (-9425 5600);
FORCEPROP 2 LAST CDS_SEC 1
J 0
(-9425 5600);
DISPLAY 1.021277 (-9425 5600);
DISPLAY INVISIBLE (-9425 5600);
FORCEADD Q_RES..1
(-9375 5725);
FORCEPROP 1 LAST PART_NUMBER CS03322FB03
J 0
(-9475 5800);
DISPLAY 0.404255 (-9475 5800);
DISPLAY INVISIBLE (-9475 5800);
FORCEPROP 1 LAST WATTAGE 1/16W
J 2
(-9150 5825);
DISPLAY 0.404255 (-9150 5825);
FORCEPROP 1 LAST PACK_TYPE 0402LF
J 0
(-9375 5825);
DISPLAY 0.404255 (-9375 5825);
FORCEPROP 1 LAST MATERIAL CHIP
J 0
(-9475 5825);
DISPLAY 0.404255 (-9475 5825);
FORCEPROP 1 LAST VALUE 33.2
J 2
(-9175 5725);
DISPLAY 0.510638 (-9175 5725);
FORCEPROP 1 LAST TOLERANCE 1%
J 0
(-9150 5725);
DISPLAY 0.510638 (-9150 5725);
FORCEPROP 1 LAST $LOCATION R2731
J 0
(-9575 5725);
DISPLAY 0.638298 (-9575 5725);
FORCEPROP 1 LASTPIN (-9475 5725) $PN 1
J 0
(-9463 5737);
DISPLAY 0.787234 (-9463 5737);
FORCEPROP 1 LASTPIN (-9275 5725) $PN 2
J 0
(-9313 5737);
DISPLAY 0.787234 (-9313 5737);
FORCEPROP 2 LAST CDS_LIB pure_quanta
J 0
(-9375 5725);
PAINT MONO (-9375 5725);
DISPLAY INVISIBLE (-9375 5725);
FORCEPROP 1 LAST PATH I25
J 0
(-9425 5875);
DISPLAY 0.978723 (-9425 5875);
PAINT WHITE (-9425 5875);
DISPLAY INVISIBLE (-9425 5875);
FORCEPROP 2 LAST CDS_LOCATION R2731
J 0
(-9425 5925);
DISPLAY 1.021277 (-9425 5925);
DISPLAY INVISIBLE (-9425 5925);
FORCEPROP 2 LAST $SEC 1
J 0
(-9425 5925);
DISPLAY 0.680851 (-9425 5925);
PAINT MONO (-9425 5925);
DISPLAY INVISIBLE (-9425 5925);
FORCEPROP 2 LAST CDS_SEC 1
J 0
(-9425 5925);
DISPLAY 1.021277 (-9425 5925);
DISPLAY INVISIBLE (-9425 5925);
FORCEADD Q_RES..1
(-9375 5675);
FORCEPROP 1 LAST PART_NUMBER CS03322FB03
J 0
(-9475 5750);
DISPLAY 0.404255 (-9475 5750);
DISPLAY INVISIBLE (-9475 5750);
FORCEPROP 1 LAST VALUE 33.2
J 2
(-9175 5675);
DISPLAY 0.510638 (-9175 5675);
FORCEPROP 1 LAST TOLERANCE 1%
J 0
(-9150 5675);
DISPLAY 0.510638 (-9150 5675);
FORCEPROP 1 LAST $LOCATION R884
J 0
(-9575 5675);
DISPLAY 0.638298 (-9575 5675);
FORCEPROP 1 LASTPIN (-9475 5675) $PN 1
J 0
(-9463 5687);
DISPLAY 0.787234 (-9463 5687);
FORCEPROP 1 LASTPIN (-9275 5675) $PN 2
J 0
(-9313 5687);
DISPLAY 0.787234 (-9313 5687);
FORCEPROP 2 LAST CDS_LIB pure_quanta
J 0
(-9375 5675);
PAINT MONO (-9375 5675);
DISPLAY INVISIBLE (-9375 5675);
FORCEPROP 1 LAST MATERIAL CHIP
J 0
(-9475 5775);
DISPLAY 0.404255 (-9475 5775);
DISPLAY INVISIBLE (-9475 5775);
FORCEPROP 1 LAST PACK_TYPE 0402LF
J 0
(-9375 5775);
DISPLAY 0.404255 (-9375 5775);
DISPLAY INVISIBLE (-9375 5775);
FORCEPROP 1 LAST WATTAGE 1/16W
J 2
(-9150 5775);
DISPLAY 0.404255 (-9150 5775);
DISPLAY INVISIBLE (-9150 5775);
FORCEPROP 1 LAST PATH I26
J 0
(-9425 5825);
DISPLAY 0.978723 (-9425 5825);
PAINT WHITE (-9425 5825);
DISPLAY INVISIBLE (-9425 5825);
FORCEPROP 1 LAST $LOCATION R884
J 0
(-9425 5875);
DISPLAY 1.021277 (-9425 5875);
DISPLAY INVISIBLE (-9425 5875);
FORCEPROP 2 LAST CDS_LOCATION R884
J 0
(-9425 5875);
DISPLAY 1.021277 (-9425 5875);
DISPLAY INVISIBLE (-9425 5875);
FORCEPROP 2 LAST $SEC 1
J 0
(-9425 5875);
DISPLAY 0.680851 (-9425 5875);
PAINT MONO (-9425 5875);
DISPLAY INVISIBLE (-9425 5875);
FORCEPROP 2 LAST CDS_SEC 1
J 0
(-9425 5875);
DISPLAY 1.021277 (-9425 5875);
DISPLAY INVISIBLE (-9425 5875);
FORCEADD Q_RES..1
(-9375 5900);
FORCEPROP 1 LAST PART_NUMBER CS03322FB03
J 0
(-9475 5975);
DISPLAY 0.404255 (-9475 5975);
DISPLAY INVISIBLE (-9475 5975);
FORCEPROP 1 LAST VALUE 33.2
J 2
(-9175 5900);
DISPLAY 0.510638 (-9175 5900);
FORCEPROP 1 LAST TOLERANCE 1%
J 0
(-9150 5900);
DISPLAY 0.510638 (-9150 5900);
FORCEPROP 1 LAST $LOCATION R2730
J 0
(-9575 5900);
DISPLAY 0.638298 (-9575 5900);
FORCEPROP 1 LASTPIN (-9475 5900) $PN 1
J 0
(-9463 5912);
DISPLAY 0.787234 (-9463 5912);
FORCEPROP 1 LASTPIN (-9275 5900) $PN 2
J 0
(-9313 5912);
DISPLAY 0.787234 (-9313 5912);
FORCEPROP 2 LAST CDS_LIB pure_quanta
J 0
(-9375 5900);
PAINT MONO (-9375 5900);
DISPLAY INVISIBLE (-9375 5900);
FORCEPROP 1 LAST MATERIAL CHIP
J 0
(-9475 6000);
DISPLAY 0.404255 (-9475 6000);
DISPLAY INVISIBLE (-9475 6000);
FORCEPROP 1 LAST PACK_TYPE 0402LF
J 0
(-9375 6000);
DISPLAY 0.404255 (-9375 6000);
DISPLAY INVISIBLE (-9375 6000);
FORCEPROP 1 LAST WATTAGE 1/16W
J 2
(-9150 6000);
DISPLAY 0.404255 (-9150 6000);
DISPLAY INVISIBLE (-9150 6000);
FORCEPROP 1 LAST PATH I27
J 0
(-9425 6050);
DISPLAY 0.978723 (-9425 6050);
PAINT WHITE (-9425 6050);
DISPLAY INVISIBLE (-9425 6050);
FORCEPROP 1 LAST $LOCATION R2730
J 0
(-9425 6100);
DISPLAY 1.021277 (-9425 6100);
DISPLAY INVISIBLE (-9425 6100);
FORCEPROP 2 LAST CDS_LOCATION R2730
J 0
(-9425 6100);
DISPLAY 1.021277 (-9425 6100);
DISPLAY INVISIBLE (-9425 6100);
FORCEPROP 2 LAST $SEC 1
J 0
(-9425 6100);
DISPLAY 0.680851 (-9425 6100);
PAINT MONO (-9425 6100);
DISPLAY INVISIBLE (-9425 6100);
FORCEPROP 2 LAST CDS_SEC 1
J 0
(-9425 6100);
DISPLAY 1.021277 (-9425 6100);
DISPLAY INVISIBLE (-9425 6100);
FORCEADD Q_RES..1
(-9375 5950);
FORCEPROP 1 LAST PART_NUMBER CS03322FB03
J 0
(-9475 6025);
DISPLAY 0.404255 (-9475 6025);
DISPLAY INVISIBLE (-9475 6025);
FORCEPROP 1 LAST VALUE 33.2
J 2
(-9175 5950);
DISPLAY 0.510638 (-9175 5950);
FORCEPROP 1 LAST TOLERANCE 1%
J 0
(-9150 5950);
DISPLAY 0.510638 (-9150 5950);
FORCEPROP 1 LAST MATERIAL CHIP
J 0
(-9475 6050);
DISPLAY 0.404255 (-9475 6050);
FORCEPROP 1 LAST WATTAGE 1/16W
J 2
(-9150 6050);
DISPLAY 0.404255 (-9150 6050);
FORCEPROP 1 LAST PACK_TYPE 0402LF
J 0
(-9375 6050);
DISPLAY 0.404255 (-9375 6050);
FORCEPROP 1 LAST $LOCATION R2729
J 0
(-9575 5950);
DISPLAY 0.638298 (-9575 5950);
FORCEPROP 1 LASTPIN (-9475 5950) $PN 1
J 0
(-9463 5962);
DISPLAY 0.787234 (-9463 5962);
FORCEPROP 1 LASTPIN (-9275 5950) $PN 2
J 0
(-9313 5962);
DISPLAY 0.787234 (-9313 5962);
FORCEPROP 2 LAST CDS_LIB pure_quanta
J 0
(-9375 5950);
PAINT MONO (-9375 5950);
DISPLAY INVISIBLE (-9375 5950);
FORCEPROP 1 LAST PATH I28
J 0
(-9425 6100);
DISPLAY 0.978723 (-9425 6100);
PAINT WHITE (-9425 6100);
DISPLAY INVISIBLE (-9425 6100);
FORCEPROP 2 LAST CDS_LOCATION R2729
J 0
(-9425 6150);
DISPLAY 1.021277 (-9425 6150);
DISPLAY INVISIBLE (-9425 6150);
FORCEPROP 2 LAST $SEC 1
J 0
(-9425 6150);
DISPLAY 0.680851 (-9425 6150);
PAINT MONO (-9425 6150);
DISPLAY INVISIBLE (-9425 6150);
FORCEPROP 2 LAST CDS_SEC 1
J 0
(-9425 6150);
DISPLAY 1.021277 (-9425 6150);
DISPLAY INVISIBLE (-9425 6150);
FORCEADD Q_RES..1
(-9375 6225);
FORCEPROP 1 LAST PART_NUMBER CS03322FB03
J 0
(-9475 6300);
DISPLAY 0.404255 (-9475 6300);
DISPLAY INVISIBLE (-9475 6300);
FORCEPROP 1 LAST VALUE 33.2
J 2
(-9175 6225);
DISPLAY 0.510638 (-9175 6225);
FORCEPROP 1 LAST TOLERANCE 1%
J 0
(-9150 6225);
DISPLAY 0.510638 (-9150 6225);
FORCEPROP 1 LAST $LOCATION R880
J 0
(-9575 6225);
DISPLAY 0.638298 (-9575 6225);
FORCEPROP 1 LASTPIN (-9475 6225) $PN 1
J 0
(-9463 6237);
DISPLAY 0.787234 (-9463 6237);
FORCEPROP 1 LASTPIN (-9275 6225) $PN 2
J 0
(-9313 6237);
DISPLAY 0.787234 (-9313 6237);
FORCEPROP 2 LAST CDS_LIB pure_quanta
J 0
(-9375 6225);
PAINT MONO (-9375 6225);
DISPLAY INVISIBLE (-9375 6225);
FORCEPROP 1 LAST MATERIAL CHIP
J 0
(-9475 6325);
DISPLAY 0.404255 (-9475 6325);
DISPLAY INVISIBLE (-9475 6325);
FORCEPROP 1 LAST PACK_TYPE 0402LF
J 0
(-9375 6325);
DISPLAY 0.404255 (-9375 6325);
DISPLAY INVISIBLE (-9375 6325);
FORCEPROP 1 LAST WATTAGE 1/16W
J 2
(-9150 6325);
DISPLAY 0.404255 (-9150 6325);
DISPLAY INVISIBLE (-9150 6325);
FORCEPROP 1 LAST PATH I29
J 0
(-9425 6375);
DISPLAY 0.978723 (-9425 6375);
PAINT WHITE (-9425 6375);
DISPLAY INVISIBLE (-9425 6375);
FORCEPROP 1 LAST $LOCATION R880
J 0
(-9425 6425);
DISPLAY 1.021277 (-9425 6425);
DISPLAY INVISIBLE (-9425 6425);
FORCEPROP 2 LAST CDS_LOCATION R880
J 0
(-9425 6425);
DISPLAY 1.021277 (-9425 6425);
DISPLAY INVISIBLE (-9425 6425);
FORCEPROP 2 LAST $SEC 1
J 0
(-9425 6425);
DISPLAY 0.680851 (-9425 6425);
PAINT MONO (-9425 6425);
DISPLAY INVISIBLE (-9425 6425);
FORCEPROP 2 LAST CDS_SEC 1
J 0
(-9425 6425);
DISPLAY 1.021277 (-9425 6425);
DISPLAY INVISIBLE (-9425 6425);
FORCEADD OFFPAGE..1
(-10450 4800);
FORCEPROP 2 LAST $XR0 95 
J 0
(-10701 4800);
DISPLAY 0.638298 (-10701 4800);
PAINT MONO (-10701 4800);
FORCEPROP 2 LAST CDS_LIB standard
J 0
(-10450 4800);
PAINT MONO (-10450 4800);
DISPLAY INVISIBLE (-10450 4800);
FORCEPROP 1 LAST OFFPAGE TRUE
J 0
(-10125 4675);
DISPLAY 0.872340 (-10125 4675);
PAINT GREEN (-10125 4675);
DISPLAY INVISIBLE (-10125 4675);
FORCEPROP 1 LAST COMMENT_BODY TRUE
J 0
(-10325 4700);
DISPLAY 0.872340 (-10325 4700);
PAINT GREEN (-10325 4700);
DISPLAY INVISIBLE (-10325 4700);
FORCEPROP 2 LAST PATH I3
J 0
(-10650 4850);
DISPLAY 1.021277 (-10650 4850);
DISPLAY INVISIBLE (-10650 4850);
FORCEADD Q_RES..1
(-9375 6275);
FORCEPROP 1 LAST PART_NUMBER CS03322FB03
J 0
(-9475 6350);
DISPLAY 0.404255 (-9475 6350);
DISPLAY INVISIBLE (-9475 6350);
FORCEPROP 1 LAST VALUE 33.2
J 2
(-9175 6275);
DISPLAY 0.510638 (-9175 6275);
FORCEPROP 1 LAST TOLERANCE 1%
J 0
(-9150 6275);
DISPLAY 0.510638 (-9150 6275);
FORCEPROP 1 LAST MATERIAL CHIP
J 0
(-9475 6375);
DISPLAY 0.404255 (-9475 6375);
FORCEPROP 1 LAST PACK_TYPE 0402LF
J 0
(-9375 6375);
DISPLAY 0.404255 (-9375 6375);
FORCEPROP 1 LAST WATTAGE 1/16W
J 2
(-9150 6375);
DISPLAY 0.404255 (-9150 6375);
FORCEPROP 1 LAST $LOCATION R2728
J 0
(-9575 6275);
DISPLAY 0.638298 (-9575 6275);
FORCEPROP 1 LASTPIN (-9475 6275) $PN 1
J 0
(-9463 6287);
DISPLAY 0.787234 (-9463 6287);
FORCEPROP 1 LASTPIN (-9275 6275) $PN 2
J 0
(-9313 6287);
DISPLAY 0.787234 (-9313 6287);
FORCEPROP 2 LAST CDS_LIB pure_quanta
J 0
(-9375 6275);
PAINT MONO (-9375 6275);
DISPLAY INVISIBLE (-9375 6275);
FORCEPROP 1 LAST PATH I30
J 0
(-9425 6425);
DISPLAY 0.978723 (-9425 6425);
PAINT WHITE (-9425 6425);
DISPLAY INVISIBLE (-9425 6425);
FORCEPROP 2 LAST CDS_LOCATION R2728
J 0
(-9425 6475);
DISPLAY 1.021277 (-9425 6475);
DISPLAY INVISIBLE (-9425 6475);
FORCEPROP 2 LAST $SEC 1
J 0
(-9425 6475);
DISPLAY 0.680851 (-9425 6475);
PAINT MONO (-9425 6475);
DISPLAY INVISIBLE (-9425 6475);
FORCEPROP 2 LAST CDS_SEC 1
J 0
(-9425 6475);
DISPLAY 1.021277 (-9425 6475);
DISPLAY INVISIBLE (-9425 6475);
FORCEADD Q_RES..1
(-9375 6450);
FORCEPROP 1 LAST PART_NUMBER CS03322FB03
J 0
(-9475 6525);
DISPLAY 0.404255 (-9475 6525);
DISPLAY INVISIBLE (-9475 6525);
FORCEPROP 1 LAST VALUE 33.2
J 2
(-9175 6450);
DISPLAY 0.510638 (-9175 6450);
FORCEPROP 1 LAST TOLERANCE 1%
J 0
(-9150 6450);
DISPLAY 0.510638 (-9150 6450);
FORCEPROP 1 LAST $LOCATION R2727
J 0
(-9575 6450);
DISPLAY 0.638298 (-9575 6450);
FORCEPROP 1 LASTPIN (-9475 6450) $PN 1
J 0
(-9463 6462);
DISPLAY 0.787234 (-9463 6462);
FORCEPROP 1 LASTPIN (-9275 6450) $PN 2
J 0
(-9313 6462);
DISPLAY 0.787234 (-9313 6462);
FORCEPROP 2 LAST CDS_LIB pure_quanta
J 0
(-9375 6450);
PAINT MONO (-9375 6450);
DISPLAY INVISIBLE (-9375 6450);
FORCEPROP 1 LAST MATERIAL CHIP
J 0
(-9475 6550);
DISPLAY 0.404255 (-9475 6550);
DISPLAY INVISIBLE (-9475 6550);
FORCEPROP 1 LAST PACK_TYPE 0402LF
J 0
(-9375 6550);
DISPLAY 0.404255 (-9375 6550);
DISPLAY INVISIBLE (-9375 6550);
FORCEPROP 1 LAST WATTAGE 1/16W
J 2
(-9150 6550);
DISPLAY 0.404255 (-9150 6550);
DISPLAY INVISIBLE (-9150 6550);
FORCEPROP 1 LAST PATH I31
J 0
(-9425 6600);
DISPLAY 0.978723 (-9425 6600);
PAINT WHITE (-9425 6600);
DISPLAY INVISIBLE (-9425 6600);
FORCEPROP 1 LAST $LOCATION R2727
J 0
(-9425 6650);
DISPLAY 1.021277 (-9425 6650);
DISPLAY INVISIBLE (-9425 6650);
FORCEPROP 2 LAST CDS_LOCATION R2727
J 0
(-9425 6650);
DISPLAY 1.021277 (-9425 6650);
DISPLAY INVISIBLE (-9425 6650);
FORCEPROP 2 LAST $SEC 1
J 0
(-9425 6650);
DISPLAY 0.680851 (-9425 6650);
PAINT MONO (-9425 6650);
DISPLAY INVISIBLE (-9425 6650);
FORCEPROP 2 LAST CDS_SEC 1
J 0
(-9425 6650);
DISPLAY 1.021277 (-9425 6650);
DISPLAY INVISIBLE (-9425 6650);
FORCEADD Q_RES..1
(-9375 6500);
FORCEPROP 1 LAST PART_NUMBER CS03322FB03
J 0
(-9475 6575);
DISPLAY 0.404255 (-9475 6575);
DISPLAY INVISIBLE (-9475 6575);
FORCEPROP 1 LAST WATTAGE 1/16W
J 2
(-9150 6600);
DISPLAY 0.404255 (-9150 6600);
FORCEPROP 1 LAST PACK_TYPE 0402LF
J 0
(-9375 6600);
DISPLAY 0.404255 (-9375 6600);
FORCEPROP 1 LAST MATERIAL CHIP
J 0
(-9475 6600);
DISPLAY 0.404255 (-9475 6600);
FORCEPROP 1 LAST TOLERANCE 1%
J 0
(-9150 6500);
DISPLAY 0.510638 (-9150 6500);
FORCEPROP 1 LAST VALUE 33.2
J 2
(-9175 6500);
DISPLAY 0.510638 (-9175 6500);
FORCEPROP 1 LAST $LOCATION R2726
J 0
(-9575 6500);
DISPLAY 0.638298 (-9575 6500);
FORCEPROP 1 LASTPIN (-9475 6500) $PN 1
J 0
(-9463 6512);
DISPLAY 0.787234 (-9463 6512);
FORCEPROP 1 LASTPIN (-9275 6500) $PN 2
J 0
(-9313 6512);
DISPLAY 0.787234 (-9313 6512);
FORCEPROP 2 LAST CDS_LIB pure_quanta
J 0
(-9375 6500);
PAINT MONO (-9375 6500);
DISPLAY INVISIBLE (-9375 6500);
FORCEPROP 1 LAST PATH I32
J 0
(-9425 6650);
DISPLAY 0.978723 (-9425 6650);
PAINT WHITE (-9425 6650);
DISPLAY INVISIBLE (-9425 6650);
FORCEPROP 2 LAST CDS_LOCATION R2726
J 0
(-9425 6700);
DISPLAY 1.021277 (-9425 6700);
DISPLAY INVISIBLE (-9425 6700);
FORCEPROP 2 LAST $SEC 1
J 0
(-9425 6700);
DISPLAY 0.680851 (-9425 6700);
PAINT MONO (-9425 6700);
DISPLAY INVISIBLE (-9425 6700);
FORCEPROP 2 LAST CDS_SEC 1
J 0
(-9425 6700);
DISPLAY 1.021277 (-9425 6700);
DISPLAY INVISIBLE (-9425 6700);
FORCEADD OFFPAGE..2
(-8300 4850);
FORCEPROP 2 LAST $XR0 115 
J 0
(-8111 4850);
DISPLAY 0.638298 (-8111 4850);
PAINT MONO (-8111 4850);
FORCEPROP 2 LAST CDS_LIB standard
J 0
(-8300 4850);
DISPLAY INVISIBLE (-8300 4850);
FORCEPROP 1 LAST OFFPAGE TRUE
J 0
(-7975 4725);
DISPLAY 0.872340 (-7975 4725);
PAINT GREEN (-7975 4725);
DISPLAY INVISIBLE (-7975 4725);
FORCEPROP 1 LAST COMMENT_BODY TRUE
J 0
(-8345 4755);
DISPLAY 0.872340 (-8345 4755);
PAINT GREEN (-8345 4755);
DISPLAY INVISIBLE (-8345 4755);
FORCEPROP 2 LAST PATH I34
J 0
(-7975 4900);
DISPLAY 1.021277 (-7975 4900);
DISPLAY INVISIBLE (-7975 4900);
FORCEADD OFFPAGE..2
(-8300 5400);
FORCEPROP 2 LAST $XR0 115 
J 0
(-8111 5400);
DISPLAY 0.638298 (-8111 5400);
PAINT MONO (-8111 5400);
FORCEPROP 2 LAST CDS_LIB standard
J 0
(-8300 5400);
DISPLAY INVISIBLE (-8300 5400);
FORCEPROP 1 LAST OFFPAGE TRUE
J 0
(-7975 5275);
DISPLAY 0.872340 (-7975 5275);
PAINT GREEN (-7975 5275);
DISPLAY INVISIBLE (-7975 5275);
FORCEPROP 1 LAST COMMENT_BODY TRUE
J 0
(-8345 5305);
DISPLAY 0.872340 (-8345 5305);
PAINT GREEN (-8345 5305);
DISPLAY INVISIBLE (-8345 5305);
FORCEPROP 2 LAST PATH I36
J 0
(-7975 5450);
DISPLAY 1.021277 (-7975 5450);
DISPLAY INVISIBLE (-7975 5450);
FORCEADD OFFPAGE..2
(-8300 5950);
FORCEPROP 2 LAST $XR0 115 
J 0
(-8111 5950);
DISPLAY 0.638298 (-8111 5950);
PAINT MONO (-8111 5950);
FORCEPROP 2 LAST CDS_LIB standard
J 0
(-8300 5950);
DISPLAY INVISIBLE (-8300 5950);
FORCEPROP 1 LAST OFFPAGE TRUE
J 0
(-7975 5825);
DISPLAY 0.872340 (-7975 5825);
PAINT GREEN (-7975 5825);
DISPLAY INVISIBLE (-7975 5825);
FORCEPROP 1 LAST COMMENT_BODY TRUE
J 0
(-8345 5855);
DISPLAY 0.872340 (-8345 5855);
PAINT GREEN (-8345 5855);
DISPLAY INVISIBLE (-8345 5855);
FORCEPROP 2 LAST PATH I38
J 0
(-7975 6000);
DISPLAY 1.021277 (-7975 6000);
DISPLAY INVISIBLE (-7975 6000);
FORCEADD OFFPAGE..1
(-6775 4625);
FORCEPROP 2 LAST $XR0 112 
J 0
(-7057 4625);
DISPLAY 0.638298 (-7057 4625);
PAINT MONO (-7057 4625);
FORCEPROP 2 LAST CDS_LIB standard
J 0
(-6775 4625);
PAINT MONO (-6775 4625);
DISPLAY INVISIBLE (-6775 4625);
FORCEPROP 1 LAST OFFPAGE TRUE
J 0
(-6450 4500);
DISPLAY 0.872340 (-6450 4500);
PAINT GREEN (-6450 4500);
DISPLAY INVISIBLE (-6450 4500);
FORCEPROP 1 LAST COMMENT_BODY TRUE
J 0
(-6650 4525);
DISPLAY 0.872340 (-6650 4525);
PAINT GREEN (-6650 4525);
DISPLAY INVISIBLE (-6650 4525);
FORCEPROP 2 LAST PATH I39
J 0
(-7025 4675);
DISPLAY 1.021277 (-7025 4675);
DISPLAY INVISIBLE (-7025 4675);
FORCEADD OFFPAGE..1
(-10450 4850);
FORCEPROP 2 LAST $XR0 94 
J 0
(-10701 4850);
DISPLAY 0.638298 (-10701 4850);
PAINT MONO (-10701 4850);
FORCEPROP 2 LAST CDS_LIB standard
J 0
(-10450 4850);
PAINT MONO (-10450 4850);
DISPLAY INVISIBLE (-10450 4850);
FORCEPROP 1 LAST OFFPAGE TRUE
J 0
(-10125 4725);
DISPLAY 0.872340 (-10125 4725);
PAINT GREEN (-10125 4725);
DISPLAY INVISIBLE (-10125 4725);
FORCEPROP 1 LAST COMMENT_BODY TRUE
J 0
(-10325 4750);
DISPLAY 0.872340 (-10325 4750);
PAINT GREEN (-10325 4750);
DISPLAY INVISIBLE (-10325 4750);
FORCEPROP 2 LAST PATH I4
J 0
(-10650 4900);
DISPLAY 1.021277 (-10650 4900);
DISPLAY INVISIBLE (-10650 4900);
FORCEADD OFFPAGE..1
(-6775 4575);
FORCEPROP 2 LAST $XR0 113 
J 0
(-7057 4575);
DISPLAY 0.638298 (-7057 4575);
PAINT MONO (-7057 4575);
FORCEPROP 2 LAST CDS_LIB standard
J 0
(-6775 4575);
PAINT MONO (-6775 4575);
DISPLAY INVISIBLE (-6775 4575);
FORCEPROP 1 LAST OFFPAGE TRUE
J 0
(-6450 4450);
DISPLAY 0.872340 (-6450 4450);
PAINT GREEN (-6450 4450);
DISPLAY INVISIBLE (-6450 4450);
FORCEPROP 1 LAST COMMENT_BODY TRUE
J 0
(-6650 4475);
DISPLAY 0.872340 (-6650 4475);
PAINT GREEN (-6650 4475);
DISPLAY INVISIBLE (-6650 4475);
FORCEPROP 2 LAST PATH I40
J 0
(-7025 4625);
DISPLAY 1.021277 (-7025 4625);
DISPLAY INVISIBLE (-7025 4625);
FORCEADD OFFPAGE..1
(-6775 5175);
FORCEPROP 2 LAST $XR0 108 
J 0
(-7057 5175);
DISPLAY 0.638298 (-7057 5175);
PAINT MONO (-7057 5175);
FORCEPROP 2 LAST CDS_LIB standard
J 0
(-6775 5175);
PAINT MONO (-6775 5175);
DISPLAY INVISIBLE (-6775 5175);
FORCEPROP 1 LAST OFFPAGE TRUE
J 0
(-6450 5050);
DISPLAY 0.872340 (-6450 5050);
PAINT GREEN (-6450 5050);
DISPLAY INVISIBLE (-6450 5050);
FORCEPROP 1 LAST COMMENT_BODY TRUE
J 0
(-6650 5075);
DISPLAY 0.872340 (-6650 5075);
PAINT GREEN (-6650 5075);
DISPLAY INVISIBLE (-6650 5075);
FORCEPROP 2 LAST PATH I41
J 0
(-7025 5225);
DISPLAY 1.021277 (-7025 5225);
DISPLAY INVISIBLE (-7025 5225);
FORCEADD OFFPAGE..1
(-6775 4850);
FORCEPROP 2 LAST $XR0 110 
J 0
(-7057 4850);
DISPLAY 0.638298 (-7057 4850);
PAINT MONO (-7057 4850);
FORCEPROP 2 LAST CDS_LIB standard
J 0
(-6775 4850);
PAINT MONO (-6775 4850);
DISPLAY INVISIBLE (-6775 4850);
FORCEPROP 1 LAST OFFPAGE TRUE
J 0
(-6450 4725);
DISPLAY 0.872340 (-6450 4725);
PAINT GREEN (-6450 4725);
DISPLAY INVISIBLE (-6450 4725);
FORCEPROP 1 LAST COMMENT_BODY TRUE
J 0
(-6650 4750);
DISPLAY 0.872340 (-6650 4750);
PAINT GREEN (-6650 4750);
DISPLAY INVISIBLE (-6650 4750);
FORCEPROP 2 LAST PATH I42
J 0
(-7025 4900);
DISPLAY 1.021277 (-7025 4900);
DISPLAY INVISIBLE (-7025 4900);
FORCEADD OFFPAGE..1
(-6775 4800);
FORCEPROP 2 LAST $XR0 111 
J 0
(-7057 4800);
DISPLAY 0.638298 (-7057 4800);
PAINT MONO (-7057 4800);
FORCEPROP 2 LAST CDS_LIB standard
J 0
(-6775 4800);
PAINT MONO (-6775 4800);
DISPLAY INVISIBLE (-6775 4800);
FORCEPROP 1 LAST OFFPAGE TRUE
J 0
(-6450 4675);
DISPLAY 0.872340 (-6450 4675);
PAINT GREEN (-6450 4675);
DISPLAY INVISIBLE (-6450 4675);
FORCEPROP 1 LAST COMMENT_BODY TRUE
J 0
(-6650 4700);
DISPLAY 0.872340 (-6650 4700);
PAINT GREEN (-6650 4700);
DISPLAY INVISIBLE (-6650 4700);
FORCEPROP 2 LAST PATH I43
J 0
(-7025 4850);
DISPLAY 1.021277 (-7025 4850);
DISPLAY INVISIBLE (-7025 4850);
FORCEADD OFFPAGE..1
(-6775 5125);
FORCEPROP 2 LAST $XR0 109 
J 0
(-7057 5125);
DISPLAY 0.638298 (-7057 5125);
PAINT MONO (-7057 5125);
FORCEPROP 2 LAST CDS_LIB standard
J 0
(-6775 5125);
PAINT MONO (-6775 5125);
DISPLAY INVISIBLE (-6775 5125);
FORCEPROP 1 LAST OFFPAGE TRUE
J 0
(-6450 5000);
DISPLAY 0.872340 (-6450 5000);
PAINT GREEN (-6450 5000);
DISPLAY INVISIBLE (-6450 5000);
FORCEPROP 1 LAST COMMENT_BODY TRUE
J 0
(-6650 5025);
DISPLAY 0.872340 (-6650 5025);
PAINT GREEN (-6650 5025);
DISPLAY INVISIBLE (-6650 5025);
FORCEPROP 2 LAST PATH I44
J 0
(-7025 5175);
DISPLAY 1.021277 (-7025 5175);
DISPLAY INVISIBLE (-7025 5175);
FORCEADD OFFPAGE..1
(-6775 5675);
FORCEPROP 2 LAST $XR0 105 
J 0
(-7057 5675);
DISPLAY 0.638298 (-7057 5675);
PAINT MONO (-7057 5675);
FORCEPROP 2 LAST CDS_LIB standard
J 0
(-6775 5675);
PAINT MONO (-6775 5675);
DISPLAY INVISIBLE (-6775 5675);
FORCEPROP 1 LAST OFFPAGE TRUE
J 0
(-6450 5550);
DISPLAY 0.872340 (-6450 5550);
PAINT GREEN (-6450 5550);
DISPLAY INVISIBLE (-6450 5550);
FORCEPROP 1 LAST COMMENT_BODY TRUE
J 0
(-6650 5575);
DISPLAY 0.872340 (-6650 5575);
PAINT GREEN (-6650 5575);
DISPLAY INVISIBLE (-6650 5575);
FORCEPROP 2 LAST PATH I45
J 0
(-7025 5725);
DISPLAY 1.021277 (-7025 5725);
DISPLAY INVISIBLE (-7025 5725);
FORCEADD OFFPAGE..1
(-6775 5350);
FORCEPROP 2 LAST $XR0 107 
J 0
(-7057 5350);
DISPLAY 0.638298 (-7057 5350);
PAINT MONO (-7057 5350);
FORCEPROP 2 LAST CDS_LIB standard
J 0
(-6775 5350);
PAINT MONO (-6775 5350);
DISPLAY INVISIBLE (-6775 5350);
FORCEPROP 1 LAST OFFPAGE TRUE
J 0
(-6450 5225);
DISPLAY 0.872340 (-6450 5225);
PAINT GREEN (-6450 5225);
DISPLAY INVISIBLE (-6450 5225);
FORCEPROP 1 LAST COMMENT_BODY TRUE
J 0
(-6650 5250);
DISPLAY 0.872340 (-6650 5250);
PAINT GREEN (-6650 5250);
DISPLAY INVISIBLE (-6650 5250);
FORCEPROP 2 LAST PATH I46
J 0
(-7025 5400);
DISPLAY 1.021277 (-7025 5400);
DISPLAY INVISIBLE (-7025 5400);
FORCEADD OFFPAGE..1
(-6775 5400);
FORCEPROP 2 LAST $XR0 106 
J 0
(-7057 5400);
DISPLAY 0.638298 (-7057 5400);
PAINT MONO (-7057 5400);
FORCEPROP 2 LAST CDS_LIB standard
J 0
(-6775 5400);
PAINT MONO (-6775 5400);
DISPLAY INVISIBLE (-6775 5400);
FORCEPROP 1 LAST OFFPAGE TRUE
J 0
(-6450 5275);
DISPLAY 0.872340 (-6450 5275);
PAINT GREEN (-6450 5275);
DISPLAY INVISIBLE (-6450 5275);
FORCEPROP 1 LAST COMMENT_BODY TRUE
J 0
(-6650 5300);
DISPLAY 0.872340 (-6650 5300);
PAINT GREEN (-6650 5300);
DISPLAY INVISIBLE (-6650 5300);
FORCEPROP 2 LAST PATH I47
J 0
(-7025 5450);
DISPLAY 1.021277 (-7025 5450);
DISPLAY INVISIBLE (-7025 5450);
FORCEADD OFFPAGE..1
(-6775 5725);
FORCEPROP 2 LAST $XR0 104 
J 0
(-7057 5725);
DISPLAY 0.638298 (-7057 5725);
PAINT MONO (-7057 5725);
FORCEPROP 2 LAST CDS_LIB standard
J 0
(-6775 5725);
PAINT MONO (-6775 5725);
DISPLAY INVISIBLE (-6775 5725);
FORCEPROP 1 LAST OFFPAGE TRUE
J 0
(-6450 5600);
DISPLAY 0.872340 (-6450 5600);
PAINT GREEN (-6450 5600);
DISPLAY INVISIBLE (-6450 5600);
FORCEPROP 1 LAST COMMENT_BODY TRUE
J 0
(-6650 5625);
DISPLAY 0.872340 (-6650 5625);
PAINT GREEN (-6650 5625);
DISPLAY INVISIBLE (-6650 5625);
FORCEPROP 2 LAST PATH I48
J 0
(-7025 5775);
DISPLAY 1.021277 (-7025 5775);
DISPLAY INVISIBLE (-7025 5775);
FORCEADD OFFPAGE..1
(-6775 5900);
FORCEPROP 2 LAST $XR0 103 
J 0
(-7057 5900);
DISPLAY 0.638298 (-7057 5900);
PAINT MONO (-7057 5900);
FORCEPROP 2 LAST CDS_LIB standard
J 0
(-6775 5900);
PAINT MONO (-6775 5900);
DISPLAY INVISIBLE (-6775 5900);
FORCEPROP 1 LAST OFFPAGE TRUE
J 0
(-6450 5775);
DISPLAY 0.872340 (-6450 5775);
PAINT GREEN (-6450 5775);
DISPLAY INVISIBLE (-6450 5775);
FORCEPROP 1 LAST COMMENT_BODY TRUE
J 0
(-6650 5800);
DISPLAY 0.872340 (-6650 5800);
PAINT GREEN (-6650 5800);
DISPLAY INVISIBLE (-6650 5800);
FORCEPROP 2 LAST PATH I49
J 0
(-7025 5950);
DISPLAY 1.021277 (-7025 5950);
DISPLAY INVISIBLE (-7025 5950);
FORCEADD OFFPAGE..1
(-10450 5125);
FORCEPROP 2 LAST $XR0 93 
J 0
(-10701 5125);
DISPLAY 0.638298 (-10701 5125);
PAINT MONO (-10701 5125);
FORCEPROP 2 LAST CDS_LIB standard
J 0
(-10450 5125);
PAINT MONO (-10450 5125);
DISPLAY INVISIBLE (-10450 5125);
FORCEPROP 1 LAST OFFPAGE TRUE
J 0
(-10125 5000);
DISPLAY 0.872340 (-10125 5000);
PAINT GREEN (-10125 5000);
DISPLAY INVISIBLE (-10125 5000);
FORCEPROP 1 LAST COMMENT_BODY TRUE
J 0
(-10325 5025);
DISPLAY 0.872340 (-10325 5025);
PAINT GREEN (-10325 5025);
DISPLAY INVISIBLE (-10325 5025);
FORCEPROP 2 LAST PATH I5
J 0
(-10650 5175);
DISPLAY 1.021277 (-10650 5175);
DISPLAY INVISIBLE (-10650 5175);
FORCEADD OFFPAGE..1
(-6775 5950);
FORCEPROP 2 LAST $XR0 102 
J 0
(-7057 5950);
DISPLAY 0.638298 (-7057 5950);
PAINT MONO (-7057 5950);
FORCEPROP 2 LAST CDS_LIB standard
J 0
(-6775 5950);
PAINT MONO (-6775 5950);
DISPLAY INVISIBLE (-6775 5950);
FORCEPROP 1 LAST OFFPAGE TRUE
J 0
(-6450 5825);
DISPLAY 0.872340 (-6450 5825);
PAINT GREEN (-6450 5825);
DISPLAY INVISIBLE (-6450 5825);
FORCEPROP 1 LAST COMMENT_BODY TRUE
J 0
(-6650 5850);
DISPLAY 0.872340 (-6650 5850);
PAINT GREEN (-6650 5850);
DISPLAY INVISIBLE (-6650 5850);
FORCEPROP 2 LAST PATH I50
J 0
(-7025 6000);
DISPLAY 1.021277 (-7025 6000);
DISPLAY INVISIBLE (-7025 6000);
FORCEADD OFFPAGE..1
(-6775 6225);
FORCEPROP 2 LAST $XR0 101 
J 0
(-7057 6225);
DISPLAY 0.638298 (-7057 6225);
PAINT MONO (-7057 6225);
FORCEPROP 2 LAST CDS_LIB standard
J 0
(-6775 6225);
PAINT MONO (-6775 6225);
DISPLAY INVISIBLE (-6775 6225);
FORCEPROP 1 LAST OFFPAGE TRUE
J 0
(-6450 6100);
DISPLAY 0.872340 (-6450 6100);
PAINT GREEN (-6450 6100);
DISPLAY INVISIBLE (-6450 6100);
FORCEPROP 1 LAST COMMENT_BODY TRUE
J 0
(-6650 6125);
DISPLAY 0.872340 (-6650 6125);
PAINT GREEN (-6650 6125);
DISPLAY INVISIBLE (-6650 6125);
FORCEPROP 2 LAST PATH I51
J 0
(-7025 6275);
DISPLAY 1.021277 (-7025 6275);
DISPLAY INVISIBLE (-7025 6275);
FORCEADD OFFPAGE..1
(-6775 6275);
FORCEPROP 2 LAST $XR0 100 
J 0
(-7057 6275);
DISPLAY 0.638298 (-7057 6275);
PAINT MONO (-7057 6275);
FORCEPROP 2 LAST CDS_LIB standard
J 0
(-6775 6275);
PAINT MONO (-6775 6275);
DISPLAY INVISIBLE (-6775 6275);
FORCEPROP 1 LAST OFFPAGE TRUE
J 0
(-6450 6150);
DISPLAY 0.872340 (-6450 6150);
PAINT GREEN (-6450 6150);
DISPLAY INVISIBLE (-6450 6150);
FORCEPROP 1 LAST COMMENT_BODY TRUE
J 0
(-6650 6175);
DISPLAY 0.872340 (-6650 6175);
PAINT GREEN (-6650 6175);
DISPLAY INVISIBLE (-6650 6175);
FORCEPROP 2 LAST PATH I53
J 0
(-7025 6325);
DISPLAY 1.021277 (-7025 6325);
DISPLAY INVISIBLE (-7025 6325);
FORCEADD OFFPAGE..2
(-8300 6500);
FORCEPROP 2 LAST $XR0 115 
J 0
(-8111 6500);
DISPLAY 0.638298 (-8111 6500);
PAINT MONO (-8111 6500);
FORCEPROP 2 LAST CDS_LIB standard
J 0
(-8300 6500);
DISPLAY INVISIBLE (-8300 6500);
FORCEPROP 1 LAST OFFPAGE TRUE
J 0
(-7975 6375);
DISPLAY 0.872340 (-7975 6375);
PAINT GREEN (-7975 6375);
DISPLAY INVISIBLE (-7975 6375);
FORCEPROP 1 LAST COMMENT_BODY TRUE
J 0
(-8345 6405);
DISPLAY 0.872340 (-8345 6405);
PAINT GREEN (-8345 6405);
DISPLAY INVISIBLE (-8345 6405);
FORCEPROP 2 LAST PATH I54
J 0
(-7975 6550);
DISPLAY 1.021277 (-7975 6550);
DISPLAY INVISIBLE (-7975 6550);
FORCEADD OFFPAGE..1
(-6775 6450);
FORCEPROP 2 LAST $XR0 99 
J 0
(-7026 6450);
DISPLAY 0.638298 (-7026 6450);
PAINT MONO (-7026 6450);
FORCEPROP 2 LAST CDS_LIB standard
J 0
(-6775 6450);
PAINT MONO (-6775 6450);
DISPLAY INVISIBLE (-6775 6450);
FORCEPROP 1 LAST OFFPAGE TRUE
J 0
(-6450 6325);
DISPLAY 0.872340 (-6450 6325);
PAINT GREEN (-6450 6325);
DISPLAY INVISIBLE (-6450 6325);
FORCEPROP 1 LAST COMMENT_BODY TRUE
J 0
(-6650 6350);
DISPLAY 0.872340 (-6650 6350);
PAINT GREEN (-6650 6350);
DISPLAY INVISIBLE (-6650 6350);
FORCEPROP 2 LAST PATH I55
J 0
(-6975 6500);
DISPLAY 1.021277 (-6975 6500);
DISPLAY INVISIBLE (-6975 6500);
FORCEADD OFFPAGE..1
(-6775 6500);
FORCEPROP 2 LAST $XR0 98 
J 0
(-7026 6500);
DISPLAY 0.638298 (-7026 6500);
PAINT MONO (-7026 6500);
FORCEPROP 2 LAST CDS_LIB standard
J 0
(-6775 6500);
PAINT MONO (-6775 6500);
DISPLAY INVISIBLE (-6775 6500);
FORCEPROP 1 LAST OFFPAGE TRUE
J 0
(-6450 6375);
DISPLAY 0.872340 (-6450 6375);
PAINT GREEN (-6450 6375);
DISPLAY INVISIBLE (-6450 6375);
FORCEPROP 1 LAST COMMENT_BODY TRUE
J 0
(-6650 6400);
DISPLAY 0.872340 (-6650 6400);
PAINT GREEN (-6650 6400);
DISPLAY INVISIBLE (-6650 6400);
FORCEPROP 2 LAST PATH I56
J 0
(-6975 6550);
DISPLAY 1.021277 (-6975 6550);
DISPLAY INVISIBLE (-6975 6550);
FORCEADD Q_RES..1
(-5700 4575);
FORCEPROP 1 LAST PART_NUMBER CS03322FB03
J 0
(-5800 4650);
DISPLAY 0.404255 (-5800 4650);
DISPLAY INVISIBLE (-5800 4650);
FORCEPROP 1 LAST TOLERANCE 1%
J 0
(-5475 4575);
DISPLAY 0.510638 (-5475 4575);
FORCEPROP 1 LAST VALUE 33.2
J 2
(-5500 4575);
DISPLAY 0.510638 (-5500 4575);
FORCEPROP 1 LAST $LOCATION R908
J 0
(-5900 4575);
DISPLAY 0.638298 (-5900 4575);
FORCEPROP 1 LASTPIN (-5800 4575) $PN 1
J 0
(-5788 4587);
DISPLAY 0.787234 (-5788 4587);
FORCEPROP 1 LASTPIN (-5600 4575) $PN 2
J 0
(-5638 4587);
DISPLAY 0.787234 (-5638 4587);
FORCEPROP 1 LAST WATTAGE 1/16W
J 2
(-5475 4675);
DISPLAY 0.404255 (-5475 4675);
DISPLAY INVISIBLE (-5475 4675);
FORCEPROP 1 LAST PACK_TYPE 0402LF
J 0
(-5700 4675);
DISPLAY 0.404255 (-5700 4675);
DISPLAY INVISIBLE (-5700 4675);
FORCEPROP 1 LAST MATERIAL CHIP
J 0
(-5800 4675);
DISPLAY 0.404255 (-5800 4675);
DISPLAY INVISIBLE (-5800 4675);
FORCEPROP 2 LAST CDS_LIB pure_quanta
J 0
(-5700 4575);
PAINT MONO (-5700 4575);
DISPLAY INVISIBLE (-5700 4575);
FORCEPROP 1 LAST PATH I57
J 0
(-5750 4725);
DISPLAY 0.978723 (-5750 4725);
PAINT WHITE (-5750 4725);
DISPLAY INVISIBLE (-5750 4725);
FORCEPROP 1 LAST $LOCATION R908
J 0
(-5750 4775);
DISPLAY 1.021277 (-5750 4775);
DISPLAY INVISIBLE (-5750 4775);
FORCEPROP 2 LAST CDS_LOCATION R908
J 0
(-5750 4775);
DISPLAY 1.021277 (-5750 4775);
DISPLAY INVISIBLE (-5750 4775);
FORCEPROP 2 LAST $SEC 1
J 0
(-5750 4775);
DISPLAY 0.680851 (-5750 4775);
PAINT MONO (-5750 4775);
DISPLAY INVISIBLE (-5750 4775);
FORCEPROP 2 LAST CDS_SEC 1
J 0
(-5750 4775);
DISPLAY 1.021277 (-5750 4775);
DISPLAY INVISIBLE (-5750 4775);
FORCEADD Q_RES..1
(-5700 4625);
FORCEPROP 1 LAST PART_NUMBER CS03322FB03
J 0
(-5800 4700);
DISPLAY 0.404255 (-5800 4700);
DISPLAY INVISIBLE (-5800 4700);
FORCEPROP 1 LAST WATTAGE 1/16W
J 2
(-5500 4725);
DISPLAY 0.404255 (-5500 4725);
FORCEPROP 1 LAST TOLERANCE 1%
J 0
(-5475 4625);
DISPLAY 0.510638 (-5475 4625);
FORCEPROP 1 LAST VALUE 33.2
J 2
(-5500 4625);
DISPLAY 0.510638 (-5500 4625);
FORCEPROP 1 LAST PACK_TYPE 0402LF
J 0
(-5700 4725);
DISPLAY 0.404255 (-5700 4725);
FORCEPROP 1 LAST MATERIAL CHIP
J 0
(-5800 4725);
DISPLAY 0.404255 (-5800 4725);
FORCEPROP 1 LAST $LOCATION R907
J 0
(-5900 4625);
DISPLAY 0.638298 (-5900 4625);
FORCEPROP 1 LASTPIN (-5800 4625) $PN 1
J 0
(-5788 4637);
DISPLAY 0.787234 (-5788 4637);
FORCEPROP 1 LASTPIN (-5600 4625) $PN 2
J 0
(-5638 4637);
DISPLAY 0.787234 (-5638 4637);
FORCEPROP 2 LAST CDS_LIB pure_quanta
J 0
(-5700 4625);
PAINT MONO (-5700 4625);
DISPLAY INVISIBLE (-5700 4625);
FORCEPROP 1 LAST PATH I58
J 0
(-5750 4775);
DISPLAY 0.978723 (-5750 4775);
PAINT WHITE (-5750 4775);
DISPLAY INVISIBLE (-5750 4775);
FORCEPROP 1 LAST $LOCATION R907
J 0
(-5750 4825);
DISPLAY 1.021277 (-5750 4825);
DISPLAY INVISIBLE (-5750 4825);
FORCEPROP 2 LAST CDS_LOCATION R907
J 0
(-5750 4825);
DISPLAY 1.021277 (-5750 4825);
DISPLAY INVISIBLE (-5750 4825);
FORCEPROP 2 LAST $SEC 1
J 0
(-5750 4825);
DISPLAY 0.680851 (-5750 4825);
PAINT MONO (-5750 4825);
DISPLAY INVISIBLE (-5750 4825);
FORCEPROP 2 LAST CDS_SEC 1
J 0
(-5750 4825);
DISPLAY 1.021277 (-5750 4825);
DISPLAY INVISIBLE (-5750 4825);
FORCEADD Q_RES..1
(-5700 4800);
FORCEPROP 1 LAST PART_NUMBER CS03322FB03
J 0
(-5800 4875);
DISPLAY 0.404255 (-5800 4875);
DISPLAY INVISIBLE (-5800 4875);
FORCEPROP 1 LAST VALUE 33.2
J 2
(-5500 4800);
DISPLAY 0.510638 (-5500 4800);
FORCEPROP 1 LAST TOLERANCE 1%
J 0
(-5475 4800);
DISPLAY 0.510638 (-5475 4800);
FORCEPROP 1 LAST $LOCATION R906
J 0
(-5900 4800);
DISPLAY 0.638298 (-5900 4800);
FORCEPROP 1 LASTPIN (-5800 4800) $PN 1
J 0
(-5788 4812);
DISPLAY 0.787234 (-5788 4812);
FORCEPROP 1 LASTPIN (-5600 4800) $PN 2
J 0
(-5638 4812);
DISPLAY 0.787234 (-5638 4812);
FORCEPROP 1 LAST WATTAGE 1/16W
J 2
(-5475 4900);
DISPLAY 0.404255 (-5475 4900);
DISPLAY INVISIBLE (-5475 4900);
FORCEPROP 1 LAST PACK_TYPE 0402LF
J 0
(-5700 4900);
DISPLAY 0.404255 (-5700 4900);
DISPLAY INVISIBLE (-5700 4900);
FORCEPROP 1 LAST MATERIAL CHIP
J 0
(-5800 4900);
DISPLAY 0.404255 (-5800 4900);
DISPLAY INVISIBLE (-5800 4900);
FORCEPROP 2 LAST CDS_LIB pure_quanta
J 0
(-5700 4800);
PAINT MONO (-5700 4800);
DISPLAY INVISIBLE (-5700 4800);
FORCEPROP 1 LAST PATH I59
J 0
(-5750 4950);
DISPLAY 0.978723 (-5750 4950);
PAINT WHITE (-5750 4950);
DISPLAY INVISIBLE (-5750 4950);
FORCEPROP 1 LAST $LOCATION R906
J 0
(-5750 5000);
DISPLAY 1.021277 (-5750 5000);
DISPLAY INVISIBLE (-5750 5000);
FORCEPROP 2 LAST CDS_LOCATION R906
J 0
(-5750 5000);
DISPLAY 1.021277 (-5750 5000);
DISPLAY INVISIBLE (-5750 5000);
FORCEPROP 2 LAST $SEC 1
J 0
(-5750 5000);
DISPLAY 0.680851 (-5750 5000);
PAINT MONO (-5750 5000);
DISPLAY INVISIBLE (-5750 5000);
FORCEPROP 2 LAST CDS_SEC 1
J 0
(-5750 5000);
DISPLAY 1.021277 (-5750 5000);
DISPLAY INVISIBLE (-5750 5000);
FORCEADD OFFPAGE..1
(-10450 5175);
FORCEPROP 2 LAST $XR0 92 
J 0
(-10701 5175);
DISPLAY 0.638298 (-10701 5175);
PAINT MONO (-10701 5175);
FORCEPROP 2 LAST CDS_LIB standard
J 0
(-10450 5175);
PAINT MONO (-10450 5175);
DISPLAY INVISIBLE (-10450 5175);
FORCEPROP 1 LAST OFFPAGE TRUE
J 0
(-10125 5050);
DISPLAY 0.872340 (-10125 5050);
PAINT GREEN (-10125 5050);
DISPLAY INVISIBLE (-10125 5050);
FORCEPROP 1 LAST COMMENT_BODY TRUE
J 0
(-10325 5075);
DISPLAY 0.872340 (-10325 5075);
PAINT GREEN (-10325 5075);
DISPLAY INVISIBLE (-10325 5075);
FORCEPROP 2 LAST PATH I6
J 0
(-10650 5225);
DISPLAY 1.021277 (-10650 5225);
DISPLAY INVISIBLE (-10650 5225);
FORCEADD Q_RES..1
(-5700 4850);
FORCEPROP 1 LAST PART_NUMBER CS03322FB03
J 0
(-5800 4925);
DISPLAY 0.404255 (-5800 4925);
DISPLAY INVISIBLE (-5800 4925);
FORCEPROP 1 LAST PACK_TYPE 0402LF
J 0
(-5700 4950);
DISPLAY 0.404255 (-5700 4950);
FORCEPROP 1 LAST MATERIAL CHIP
J 0
(-5800 4950);
DISPLAY 0.404255 (-5800 4950);
FORCEPROP 1 LAST VALUE 33.2
J 2
(-5500 4850);
DISPLAY 0.510638 (-5500 4850);
FORCEPROP 1 LAST TOLERANCE 1%
J 0
(-5475 4850);
DISPLAY 0.510638 (-5475 4850);
FORCEPROP 1 LAST WATTAGE 1/16W
J 2
(-5475 4950);
DISPLAY 0.404255 (-5475 4950);
FORCEPROP 1 LAST $LOCATION R905
J 0
(-5900 4850);
DISPLAY 0.638298 (-5900 4850);
FORCEPROP 1 LASTPIN (-5800 4850) $PN 1
J 0
(-5788 4862);
DISPLAY 0.787234 (-5788 4862);
FORCEPROP 1 LASTPIN (-5600 4850) $PN 2
J 0
(-5638 4862);
DISPLAY 0.787234 (-5638 4862);
FORCEPROP 2 LAST CDS_LIB pure_quanta
J 0
(-5700 4850);
PAINT MONO (-5700 4850);
DISPLAY INVISIBLE (-5700 4850);
FORCEPROP 1 LAST PATH I60
J 0
(-5750 5000);
DISPLAY 0.978723 (-5750 5000);
PAINT WHITE (-5750 5000);
DISPLAY INVISIBLE (-5750 5000);
FORCEPROP 1 LAST $LOCATION R905
J 0
(-5750 5050);
DISPLAY 1.021277 (-5750 5050);
DISPLAY INVISIBLE (-5750 5050);
FORCEPROP 2 LAST CDS_LOCATION R905
J 0
(-5750 5050);
DISPLAY 1.021277 (-5750 5050);
DISPLAY INVISIBLE (-5750 5050);
FORCEPROP 2 LAST $SEC 1
J 0
(-5750 5050);
DISPLAY 0.680851 (-5750 5050);
PAINT MONO (-5750 5050);
DISPLAY INVISIBLE (-5750 5050);
FORCEPROP 2 LAST CDS_SEC 1
J 0
(-5750 5050);
DISPLAY 1.021277 (-5750 5050);
DISPLAY INVISIBLE (-5750 5050);
FORCEADD Q_RES..1
(-5700 5125);
FORCEPROP 1 LAST PART_NUMBER CS03322FB03
J 0
(-5800 5200);
DISPLAY 0.404255 (-5800 5200);
DISPLAY INVISIBLE (-5800 5200);
FORCEPROP 1 LAST VALUE 33.2
J 2
(-5500 5125);
DISPLAY 0.510638 (-5500 5125);
FORCEPROP 1 LAST TOLERANCE 1%
J 0
(-5475 5125);
DISPLAY 0.510638 (-5475 5125);
FORCEPROP 1 LAST $LOCATION R2736
J 0
(-5900 5125);
DISPLAY 0.638298 (-5900 5125);
FORCEPROP 1 LASTPIN (-5800 5125) $PN 1
J 0
(-5788 5137);
DISPLAY 0.787234 (-5788 5137);
FORCEPROP 1 LASTPIN (-5600 5125) $PN 2
J 0
(-5638 5137);
DISPLAY 0.787234 (-5638 5137);
FORCEPROP 1 LAST WATTAGE 1/16W
J 2
(-5475 5225);
DISPLAY 0.404255 (-5475 5225);
DISPLAY INVISIBLE (-5475 5225);
FORCEPROP 1 LAST PACK_TYPE 0402LF
J 0
(-5700 5225);
DISPLAY 0.404255 (-5700 5225);
DISPLAY INVISIBLE (-5700 5225);
FORCEPROP 1 LAST MATERIAL CHIP
J 0
(-5800 5225);
DISPLAY 0.404255 (-5800 5225);
DISPLAY INVISIBLE (-5800 5225);
FORCEPROP 2 LAST CDS_LIB pure_quanta
J 0
(-5700 5125);
PAINT MONO (-5700 5125);
DISPLAY INVISIBLE (-5700 5125);
FORCEPROP 1 LAST PATH I61
J 0
(-5750 5275);
DISPLAY 0.978723 (-5750 5275);
PAINT WHITE (-5750 5275);
DISPLAY INVISIBLE (-5750 5275);
FORCEPROP 2 LAST CDS_LOCATION R2736
J 0
(-5750 5325);
DISPLAY 1.021277 (-5750 5325);
DISPLAY INVISIBLE (-5750 5325);
FORCEPROP 2 LAST $SEC 1
J 0
(-5750 5325);
DISPLAY 0.680851 (-5750 5325);
PAINT MONO (-5750 5325);
DISPLAY INVISIBLE (-5750 5325);
FORCEPROP 2 LAST CDS_SEC 1
J 0
(-5750 5325);
DISPLAY 1.021277 (-5750 5325);
DISPLAY INVISIBLE (-5750 5325);
FORCEADD Q_RES..1
(-5700 5175);
FORCEPROP 1 LAST PART_NUMBER CS03322FB03
J 0
(-5800 5250);
DISPLAY 0.404255 (-5800 5250);
DISPLAY INVISIBLE (-5800 5250);
FORCEPROP 1 LAST WATTAGE 1/16W
J 2
(-5500 5275);
DISPLAY 0.404255 (-5500 5275);
FORCEPROP 1 LAST VALUE 33.2
J 2
(-5500 5175);
DISPLAY 0.510638 (-5500 5175);
FORCEPROP 1 LAST TOLERANCE 1%
J 0
(-5475 5175);
DISPLAY 0.510638 (-5475 5175);
FORCEPROP 1 LAST PACK_TYPE 0402LF
J 0
(-5700 5275);
DISPLAY 0.404255 (-5700 5275);
FORCEPROP 1 LAST MATERIAL CHIP
J 0
(-5800 5275);
DISPLAY 0.404255 (-5800 5275);
FORCEPROP 1 LAST $LOCATION R903
J 0
(-5900 5175);
DISPLAY 0.638298 (-5900 5175);
FORCEPROP 1 LASTPIN (-5800 5175) $PN 1
J 0
(-5788 5187);
DISPLAY 0.787234 (-5788 5187);
FORCEPROP 1 LASTPIN (-5600 5175) $PN 2
J 0
(-5638 5187);
DISPLAY 0.787234 (-5638 5187);
FORCEPROP 2 LAST CDS_LIB pure_quanta
J 0
(-5700 5175);
PAINT MONO (-5700 5175);
DISPLAY INVISIBLE (-5700 5175);
FORCEPROP 1 LAST PATH I62
J 0
(-5750 5325);
DISPLAY 0.978723 (-5750 5325);
PAINT WHITE (-5750 5325);
DISPLAY INVISIBLE (-5750 5325);
FORCEPROP 1 LAST $LOCATION R903
J 0
(-5750 5375);
DISPLAY 1.021277 (-5750 5375);
DISPLAY INVISIBLE (-5750 5375);
FORCEPROP 2 LAST CDS_LOCATION R903
J 0
(-5750 5375);
DISPLAY 1.021277 (-5750 5375);
DISPLAY INVISIBLE (-5750 5375);
FORCEPROP 2 LAST $SEC 1
J 0
(-5750 5375);
DISPLAY 0.680851 (-5750 5375);
PAINT MONO (-5750 5375);
DISPLAY INVISIBLE (-5750 5375);
FORCEPROP 2 LAST CDS_SEC 1
J 0
(-5750 5375);
DISPLAY 1.021277 (-5750 5375);
DISPLAY INVISIBLE (-5750 5375);
FORCEADD Q_RES..1
(-5700 5350);
FORCEPROP 1 LAST PART_NUMBER CS03322FB03
J 0
(-5800 5425);
DISPLAY 0.404255 (-5800 5425);
DISPLAY INVISIBLE (-5800 5425);
FORCEPROP 1 LAST VALUE 33.2
J 2
(-5500 5350);
DISPLAY 0.510638 (-5500 5350);
FORCEPROP 1 LAST TOLERANCE 1%
J 0
(-5475 5350);
DISPLAY 0.510638 (-5475 5350);
FORCEPROP 1 LAST $LOCATION R902
J 0
(-5900 5350);
DISPLAY 0.638298 (-5900 5350);
FORCEPROP 1 LASTPIN (-5800 5350) $PN 1
J 0
(-5788 5362);
DISPLAY 0.787234 (-5788 5362);
FORCEPROP 1 LASTPIN (-5600 5350) $PN 2
J 0
(-5638 5362);
DISPLAY 0.787234 (-5638 5362);
FORCEPROP 1 LAST WATTAGE 1/16W
J 2
(-5475 5450);
DISPLAY 0.404255 (-5475 5450);
DISPLAY INVISIBLE (-5475 5450);
FORCEPROP 1 LAST PACK_TYPE 0402LF
J 0
(-5700 5450);
DISPLAY 0.404255 (-5700 5450);
DISPLAY INVISIBLE (-5700 5450);
FORCEPROP 1 LAST MATERIAL CHIP
J 0
(-5800 5450);
DISPLAY 0.404255 (-5800 5450);
DISPLAY INVISIBLE (-5800 5450);
FORCEPROP 2 LAST CDS_LIB pure_quanta
J 0
(-5700 5350);
PAINT MONO (-5700 5350);
DISPLAY INVISIBLE (-5700 5350);
FORCEPROP 1 LAST PATH I63
J 0
(-5750 5500);
DISPLAY 0.978723 (-5750 5500);
PAINT WHITE (-5750 5500);
DISPLAY INVISIBLE (-5750 5500);
FORCEPROP 1 LAST $LOCATION R902
J 0
(-5750 5550);
DISPLAY 1.021277 (-5750 5550);
DISPLAY INVISIBLE (-5750 5550);
FORCEPROP 2 LAST CDS_LOCATION R902
J 0
(-5750 5550);
DISPLAY 1.021277 (-5750 5550);
DISPLAY INVISIBLE (-5750 5550);
FORCEPROP 2 LAST $SEC 1
J 0
(-5750 5550);
DISPLAY 0.680851 (-5750 5550);
PAINT MONO (-5750 5550);
DISPLAY INVISIBLE (-5750 5550);
FORCEPROP 2 LAST CDS_SEC 1
J 0
(-5750 5550);
DISPLAY 1.021277 (-5750 5550);
DISPLAY INVISIBLE (-5750 5550);
FORCEADD Q_RES..1
(-5700 5400);
FORCEPROP 1 LAST PART_NUMBER CS03322FB03
J 0
(-5800 5475);
DISPLAY 0.404255 (-5800 5475);
DISPLAY INVISIBLE (-5800 5475);
FORCEPROP 1 LAST WATTAGE 1/16W
J 2
(-5475 5500);
DISPLAY 0.404255 (-5475 5500);
FORCEPROP 1 LAST TOLERANCE 1%
J 0
(-5475 5400);
DISPLAY 0.510638 (-5475 5400);
FORCEPROP 1 LAST PACK_TYPE 0402LF
J 0
(-5700 5500);
DISPLAY 0.404255 (-5700 5500);
FORCEPROP 1 LAST VALUE 33.2
J 2
(-5500 5400);
DISPLAY 0.510638 (-5500 5400);
FORCEPROP 1 LAST MATERIAL CHIP
J 0
(-5800 5500);
DISPLAY 0.404255 (-5800 5500);
FORCEPROP 1 LAST $LOCATION R901
J 0
(-5900 5400);
DISPLAY 0.638298 (-5900 5400);
FORCEPROP 1 LASTPIN (-5800 5400) $PN 1
J 0
(-5788 5412);
DISPLAY 0.787234 (-5788 5412);
FORCEPROP 1 LASTPIN (-5600 5400) $PN 2
J 0
(-5638 5412);
DISPLAY 0.787234 (-5638 5412);
FORCEPROP 2 LAST CDS_LIB pure_quanta
J 0
(-5700 5400);
PAINT MONO (-5700 5400);
DISPLAY INVISIBLE (-5700 5400);
FORCEPROP 1 LAST PATH I64
J 0
(-5750 5550);
DISPLAY 0.978723 (-5750 5550);
PAINT WHITE (-5750 5550);
DISPLAY INVISIBLE (-5750 5550);
FORCEPROP 1 LAST $LOCATION R901
J 0
(-5750 5600);
DISPLAY 1.021277 (-5750 5600);
DISPLAY INVISIBLE (-5750 5600);
FORCEPROP 2 LAST CDS_LOCATION R901
J 0
(-5750 5600);
DISPLAY 1.021277 (-5750 5600);
DISPLAY INVISIBLE (-5750 5600);
FORCEPROP 2 LAST $SEC 1
J 0
(-5750 5600);
DISPLAY 0.680851 (-5750 5600);
PAINT MONO (-5750 5600);
DISPLAY INVISIBLE (-5750 5600);
FORCEPROP 2 LAST CDS_SEC 1
J 0
(-5750 5600);
DISPLAY 1.021277 (-5750 5600);
DISPLAY INVISIBLE (-5750 5600);
FORCEADD Q_RES..1
(-5700 5725);
FORCEPROP 1 LAST PART_NUMBER CS03322FB03
J 0
(-5800 5800);
DISPLAY 0.404255 (-5800 5800);
DISPLAY INVISIBLE (-5800 5800);
FORCEPROP 1 LAST VALUE 33.2
J 2
(-5500 5725);
DISPLAY 0.510638 (-5500 5725);
FORCEPROP 1 LAST TOLERANCE 1%
J 0
(-5475 5725);
DISPLAY 0.510638 (-5475 5725);
FORCEPROP 1 LAST WATTAGE 1/16W
J 2
(-5500 5825);
DISPLAY 0.404255 (-5500 5825);
FORCEPROP 1 LAST PACK_TYPE 0402LF
J 0
(-5700 5825);
DISPLAY 0.404255 (-5700 5825);
FORCEPROP 1 LAST MATERIAL CHIP
J 0
(-5800 5825);
DISPLAY 0.404255 (-5800 5825);
FORCEPROP 1 LAST $LOCATION R899
J 0
(-5900 5725);
DISPLAY 0.638298 (-5900 5725);
FORCEPROP 1 LASTPIN (-5800 5725) $PN 1
J 0
(-5788 5737);
DISPLAY 0.787234 (-5788 5737);
FORCEPROP 1 LASTPIN (-5600 5725) $PN 2
J 0
(-5638 5737);
DISPLAY 0.787234 (-5638 5737);
FORCEPROP 2 LAST CDS_LIB pure_quanta
J 0
(-5700 5725);
PAINT MONO (-5700 5725);
DISPLAY INVISIBLE (-5700 5725);
FORCEPROP 1 LAST PATH I65
J 0
(-5750 5875);
DISPLAY 0.978723 (-5750 5875);
PAINT WHITE (-5750 5875);
DISPLAY INVISIBLE (-5750 5875);
FORCEPROP 1 LAST $LOCATION R899
J 0
(-5750 5925);
DISPLAY 1.021277 (-5750 5925);
DISPLAY INVISIBLE (-5750 5925);
FORCEPROP 2 LAST CDS_LOCATION R899
J 0
(-5750 5925);
DISPLAY 1.021277 (-5750 5925);
DISPLAY INVISIBLE (-5750 5925);
FORCEPROP 2 LAST $SEC 1
J 0
(-5750 5925);
DISPLAY 0.680851 (-5750 5925);
PAINT MONO (-5750 5925);
DISPLAY INVISIBLE (-5750 5925);
FORCEPROP 2 LAST CDS_SEC 1
J 0
(-5750 5925);
DISPLAY 1.021277 (-5750 5925);
DISPLAY INVISIBLE (-5750 5925);
FORCEADD Q_RES..1
(-5700 5675);
FORCEPROP 1 LAST PART_NUMBER CS03322FB03
J 0
(-5800 5750);
DISPLAY 0.404255 (-5800 5750);
DISPLAY INVISIBLE (-5800 5750);
FORCEPROP 1 LAST TOLERANCE 1%
J 0
(-5475 5675);
DISPLAY 0.510638 (-5475 5675);
FORCEPROP 1 LAST VALUE 33.2
J 2
(-5500 5675);
DISPLAY 0.510638 (-5500 5675);
FORCEPROP 1 LAST $LOCATION R900
J 0
(-5900 5675);
DISPLAY 0.638298 (-5900 5675);
FORCEPROP 1 LASTPIN (-5800 5675) $PN 1
J 0
(-5788 5687);
DISPLAY 0.787234 (-5788 5687);
FORCEPROP 1 LASTPIN (-5600 5675) $PN 2
J 0
(-5638 5687);
DISPLAY 0.787234 (-5638 5687);
FORCEPROP 2 LAST CDS_LIB pure_quanta
J 0
(-5700 5675);
PAINT MONO (-5700 5675);
DISPLAY INVISIBLE (-5700 5675);
FORCEPROP 1 LAST MATERIAL CHIP
J 0
(-5800 5775);
DISPLAY 0.404255 (-5800 5775);
DISPLAY INVISIBLE (-5800 5775);
FORCEPROP 1 LAST PACK_TYPE 0402LF
J 0
(-5700 5775);
DISPLAY 0.404255 (-5700 5775);
DISPLAY INVISIBLE (-5700 5775);
FORCEPROP 1 LAST WATTAGE 1/16W
J 2
(-5475 5775);
DISPLAY 0.404255 (-5475 5775);
DISPLAY INVISIBLE (-5475 5775);
FORCEPROP 1 LAST PATH I66
J 0
(-5750 5825);
DISPLAY 0.978723 (-5750 5825);
PAINT WHITE (-5750 5825);
DISPLAY INVISIBLE (-5750 5825);
FORCEPROP 1 LAST $LOCATION R900
J 0
(-5750 5875);
DISPLAY 1.021277 (-5750 5875);
DISPLAY INVISIBLE (-5750 5875);
FORCEPROP 2 LAST CDS_LOCATION R900
J 0
(-5750 5875);
DISPLAY 1.021277 (-5750 5875);
DISPLAY INVISIBLE (-5750 5875);
FORCEPROP 2 LAST $SEC 1
J 0
(-5750 5875);
DISPLAY 0.680851 (-5750 5875);
PAINT MONO (-5750 5875);
DISPLAY INVISIBLE (-5750 5875);
FORCEPROP 2 LAST CDS_SEC 1
J 0
(-5750 5875);
DISPLAY 1.021277 (-5750 5875);
DISPLAY INVISIBLE (-5750 5875);
FORCEADD Q_RES..1
(-5700 5950);
FORCEPROP 1 LAST PART_NUMBER CS03322FB03
J 0
(-5800 6025);
DISPLAY 0.404255 (-5800 6025);
DISPLAY INVISIBLE (-5800 6025);
FORCEPROP 1 LAST MATERIAL CHIP
J 0
(-5800 6050);
DISPLAY 0.404255 (-5800 6050);
FORCEPROP 1 LAST PACK_TYPE 0402LF
J 0
(-5700 6050);
DISPLAY 0.404255 (-5700 6050);
FORCEPROP 1 LAST WATTAGE 1/16W
J 2
(-5475 6050);
DISPLAY 0.404255 (-5475 6050);
FORCEPROP 1 LAST TOLERANCE 1%
J 0
(-5475 5950);
DISPLAY 0.510638 (-5475 5950);
FORCEPROP 1 LAST VALUE 33.2
J 2
(-5500 5950);
DISPLAY 0.510638 (-5500 5950);
FORCEPROP 1 LAST $LOCATION R897
J 0
(-5900 5950);
DISPLAY 0.638298 (-5900 5950);
FORCEPROP 1 LASTPIN (-5800 5950) $PN 1
J 0
(-5788 5962);
DISPLAY 0.787234 (-5788 5962);
FORCEPROP 1 LASTPIN (-5600 5950) $PN 2
J 0
(-5638 5962);
DISPLAY 0.787234 (-5638 5962);
FORCEPROP 2 LAST CDS_LIB pure_quanta
J 0
(-5700 5950);
PAINT MONO (-5700 5950);
DISPLAY INVISIBLE (-5700 5950);
FORCEPROP 1 LAST PATH I67
J 0
(-5750 6100);
DISPLAY 0.978723 (-5750 6100);
PAINT WHITE (-5750 6100);
DISPLAY INVISIBLE (-5750 6100);
FORCEPROP 1 LAST $LOCATION R897
J 0
(-5750 6150);
DISPLAY 1.021277 (-5750 6150);
DISPLAY INVISIBLE (-5750 6150);
FORCEPROP 2 LAST CDS_LOCATION R897
J 0
(-5750 6150);
DISPLAY 1.021277 (-5750 6150);
DISPLAY INVISIBLE (-5750 6150);
FORCEPROP 2 LAST $SEC 1
J 0
(-5750 6150);
DISPLAY 0.680851 (-5750 6150);
PAINT MONO (-5750 6150);
DISPLAY INVISIBLE (-5750 6150);
FORCEPROP 2 LAST CDS_SEC 1
J 0
(-5750 6150);
DISPLAY 1.021277 (-5750 6150);
DISPLAY INVISIBLE (-5750 6150);
FORCEADD Q_RES..1
(-5700 5900);
FORCEPROP 1 LAST PART_NUMBER CS03322FB03
J 0
(-5800 5975);
DISPLAY 0.404255 (-5800 5975);
DISPLAY INVISIBLE (-5800 5975);
FORCEPROP 1 LAST VALUE 33.2
J 2
(-5500 5900);
DISPLAY 0.510638 (-5500 5900);
FORCEPROP 1 LAST TOLERANCE 1%
J 0
(-5475 5900);
DISPLAY 0.510638 (-5475 5900);
FORCEPROP 1 LAST $LOCATION R898
J 0
(-5900 5900);
DISPLAY 0.638298 (-5900 5900);
FORCEPROP 1 LASTPIN (-5800 5900) $PN 1
J 0
(-5788 5912);
DISPLAY 0.787234 (-5788 5912);
FORCEPROP 1 LASTPIN (-5600 5900) $PN 2
J 0
(-5638 5912);
DISPLAY 0.787234 (-5638 5912);
FORCEPROP 2 LAST CDS_LIB pure_quanta
J 0
(-5700 5900);
PAINT MONO (-5700 5900);
DISPLAY INVISIBLE (-5700 5900);
FORCEPROP 1 LAST MATERIAL CHIP
J 0
(-5800 6000);
DISPLAY 0.404255 (-5800 6000);
DISPLAY INVISIBLE (-5800 6000);
FORCEPROP 1 LAST PACK_TYPE 0402LF
J 0
(-5700 6000);
DISPLAY 0.404255 (-5700 6000);
DISPLAY INVISIBLE (-5700 6000);
FORCEPROP 1 LAST WATTAGE 1/16W
J 2
(-5475 6000);
DISPLAY 0.404255 (-5475 6000);
DISPLAY INVISIBLE (-5475 6000);
FORCEPROP 1 LAST PATH I68
J 0
(-5750 6050);
DISPLAY 0.978723 (-5750 6050);
PAINT WHITE (-5750 6050);
DISPLAY INVISIBLE (-5750 6050);
FORCEPROP 1 LAST $LOCATION R898
J 0
(-5750 6100);
DISPLAY 1.021277 (-5750 6100);
DISPLAY INVISIBLE (-5750 6100);
FORCEPROP 2 LAST CDS_LOCATION R898
J 0
(-5750 6100);
DISPLAY 1.021277 (-5750 6100);
DISPLAY INVISIBLE (-5750 6100);
FORCEPROP 2 LAST $SEC 1
J 0
(-5750 6100);
DISPLAY 0.680851 (-5750 6100);
PAINT MONO (-5750 6100);
DISPLAY INVISIBLE (-5750 6100);
FORCEPROP 2 LAST CDS_SEC 1
J 0
(-5750 6100);
DISPLAY 1.021277 (-5750 6100);
DISPLAY INVISIBLE (-5750 6100);
FORCEADD Q_RES..1
(-5700 6225);
FORCEPROP 1 LAST PART_NUMBER CS03322FB03
J 0
(-5800 6300);
DISPLAY 0.404255 (-5800 6300);
DISPLAY INVISIBLE (-5800 6300);
FORCEPROP 1 LAST VALUE 33.2
J 2
(-5500 6225);
DISPLAY 0.510638 (-5500 6225);
FORCEPROP 1 LAST TOLERANCE 1%
J 0
(-5475 6225);
DISPLAY 0.510638 (-5475 6225);
FORCEPROP 1 LAST $LOCATION R896
J 0
(-5900 6225);
DISPLAY 0.638298 (-5900 6225);
FORCEPROP 1 LASTPIN (-5800 6225) $PN 1
J 0
(-5788 6237);
DISPLAY 0.787234 (-5788 6237);
FORCEPROP 1 LASTPIN (-5600 6225) $PN 2
J 0
(-5638 6237);
DISPLAY 0.787234 (-5638 6237);
FORCEPROP 1 LAST WATTAGE 1/16W
J 2
(-5475 6325);
DISPLAY 0.404255 (-5475 6325);
DISPLAY INVISIBLE (-5475 6325);
FORCEPROP 1 LAST PACK_TYPE 0402LF
J 0
(-5700 6325);
DISPLAY 0.404255 (-5700 6325);
DISPLAY INVISIBLE (-5700 6325);
FORCEPROP 1 LAST MATERIAL CHIP
J 0
(-5800 6325);
DISPLAY 0.404255 (-5800 6325);
DISPLAY INVISIBLE (-5800 6325);
FORCEPROP 2 LAST CDS_LIB pure_quanta
J 0
(-5700 6225);
PAINT MONO (-5700 6225);
DISPLAY INVISIBLE (-5700 6225);
FORCEPROP 1 LAST PATH I69
J 0
(-5750 6375);
DISPLAY 0.978723 (-5750 6375);
PAINT WHITE (-5750 6375);
DISPLAY INVISIBLE (-5750 6375);
FORCEPROP 1 LAST $LOCATION R896
J 0
(-5750 6425);
DISPLAY 1.021277 (-5750 6425);
DISPLAY INVISIBLE (-5750 6425);
FORCEPROP 2 LAST CDS_LOCATION R896
J 0
(-5750 6425);
DISPLAY 1.021277 (-5750 6425);
DISPLAY INVISIBLE (-5750 6425);
FORCEPROP 2 LAST $SEC 1
J 0
(-5750 6425);
DISPLAY 0.680851 (-5750 6425);
PAINT MONO (-5750 6425);
DISPLAY INVISIBLE (-5750 6425);
FORCEPROP 2 LAST CDS_SEC 1
J 0
(-5750 6425);
DISPLAY 1.021277 (-5750 6425);
DISPLAY INVISIBLE (-5750 6425);
FORCEADD OFFPAGE..1
(-10450 5350);
FORCEPROP 2 LAST $XR0 91 
J 0
(-10701 5350);
DISPLAY 0.638298 (-10701 5350);
PAINT MONO (-10701 5350);
FORCEPROP 2 LAST CDS_LIB standard
J 0
(-10450 5350);
PAINT MONO (-10450 5350);
DISPLAY INVISIBLE (-10450 5350);
FORCEPROP 1 LAST OFFPAGE TRUE
J 0
(-10125 5225);
DISPLAY 0.872340 (-10125 5225);
PAINT GREEN (-10125 5225);
DISPLAY INVISIBLE (-10125 5225);
FORCEPROP 1 LAST COMMENT_BODY TRUE
J 0
(-10325 5250);
DISPLAY 0.872340 (-10325 5250);
PAINT GREEN (-10325 5250);
DISPLAY INVISIBLE (-10325 5250);
FORCEPROP 2 LAST PATH I7
J 0
(-10650 5400);
DISPLAY 1.021277 (-10650 5400);
DISPLAY INVISIBLE (-10650 5400);
FORCEADD OFFPAGE..2
(-4625 4850);
FORCEPROP 2 LAST $XR0 115 
J 0
(-4436 4850);
DISPLAY 0.638298 (-4436 4850);
PAINT MONO (-4436 4850);
FORCEPROP 2 LAST CDS_LIB standard
J 0
(-4625 4850);
DISPLAY INVISIBLE (-4625 4850);
FORCEPROP 1 LAST OFFPAGE TRUE
J 0
(-4300 4725);
DISPLAY 0.872340 (-4300 4725);
PAINT GREEN (-4300 4725);
DISPLAY INVISIBLE (-4300 4725);
FORCEPROP 1 LAST COMMENT_BODY TRUE
J 0
(-4670 4755);
DISPLAY 0.872340 (-4670 4755);
PAINT GREEN (-4670 4755);
DISPLAY INVISIBLE (-4670 4755);
FORCEPROP 2 LAST PATH I71
J 0
(-4300 4900);
DISPLAY 1.021277 (-4300 4900);
DISPLAY INVISIBLE (-4300 4900);
FORCEADD OFFPAGE..2
(-4625 5400);
FORCEPROP 2 LAST $XR0 115 
J 0
(-4436 5400);
DISPLAY 0.638298 (-4436 5400);
PAINT MONO (-4436 5400);
FORCEPROP 2 LAST CDS_LIB standard
J 0
(-4625 5400);
DISPLAY INVISIBLE (-4625 5400);
FORCEPROP 1 LAST OFFPAGE TRUE
J 0
(-4300 5275);
DISPLAY 0.872340 (-4300 5275);
PAINT GREEN (-4300 5275);
DISPLAY INVISIBLE (-4300 5275);
FORCEPROP 1 LAST COMMENT_BODY TRUE
J 0
(-4670 5305);
DISPLAY 0.872340 (-4670 5305);
PAINT GREEN (-4670 5305);
DISPLAY INVISIBLE (-4670 5305);
FORCEPROP 2 LAST PATH I74
J 0
(-4300 5450);
DISPLAY 1.021277 (-4300 5450);
DISPLAY INVISIBLE (-4300 5450);
FORCEADD OFFPAGE..2
(-4625 5950);
FORCEPROP 2 LAST $XR0 115 
J 0
(-4436 5950);
DISPLAY 0.638298 (-4436 5950);
PAINT MONO (-4436 5950);
FORCEPROP 2 LAST CDS_LIB standard
J 0
(-4625 5950);
DISPLAY INVISIBLE (-4625 5950);
FORCEPROP 1 LAST OFFPAGE TRUE
J 0
(-4300 5825);
DISPLAY 0.872340 (-4300 5825);
PAINT GREEN (-4300 5825);
DISPLAY INVISIBLE (-4300 5825);
FORCEPROP 1 LAST COMMENT_BODY TRUE
J 0
(-4670 5855);
DISPLAY 0.872340 (-4670 5855);
PAINT GREEN (-4670 5855);
DISPLAY INVISIBLE (-4670 5855);
FORCEPROP 2 LAST PATH I75
J 0
(-4300 6000);
DISPLAY 1.021277 (-4300 6000);
DISPLAY INVISIBLE (-4300 6000);
FORCEADD Q_RES..1
(-5700 6275);
FORCEPROP 1 LAST PART_NUMBER CS03322FB03
J 0
(-5800 6350);
DISPLAY 0.404255 (-5800 6350);
DISPLAY INVISIBLE (-5800 6350);
FORCEPROP 1 LAST WATTAGE 1/16W
J 2
(-5475 6375);
DISPLAY 0.404255 (-5475 6375);
FORCEPROP 1 LAST VALUE 33.2
J 2
(-5500 6275);
DISPLAY 0.510638 (-5500 6275);
FORCEPROP 1 LAST TOLERANCE 1%
J 0
(-5475 6275);
DISPLAY 0.510638 (-5475 6275);
FORCEPROP 1 LAST MATERIAL CHIP
J 0
(-5800 6375);
DISPLAY 0.404255 (-5800 6375);
FORCEPROP 1 LAST PACK_TYPE 0402LF
J 0
(-5700 6375);
DISPLAY 0.404255 (-5700 6375);
FORCEPROP 1 LAST $LOCATION R895
J 0
(-5900 6275);
DISPLAY 0.638298 (-5900 6275);
FORCEPROP 1 LASTPIN (-5800 6275) $PN 1
J 0
(-5788 6287);
DISPLAY 0.787234 (-5788 6287);
FORCEPROP 1 LASTPIN (-5600 6275) $PN 2
J 0
(-5638 6287);
DISPLAY 0.787234 (-5638 6287);
FORCEPROP 2 LAST CDS_LIB pure_quanta
J 0
(-5700 6275);
PAINT MONO (-5700 6275);
DISPLAY INVISIBLE (-5700 6275);
FORCEPROP 1 LAST PATH I77
J 0
(-5750 6425);
DISPLAY 0.978723 (-5750 6425);
PAINT WHITE (-5750 6425);
DISPLAY INVISIBLE (-5750 6425);
FORCEPROP 1 LAST $LOCATION R895
J 0
(-5750 6475);
DISPLAY 1.021277 (-5750 6475);
DISPLAY INVISIBLE (-5750 6475);
FORCEPROP 2 LAST CDS_LOCATION R895
J 0
(-5750 6475);
DISPLAY 1.021277 (-5750 6475);
DISPLAY INVISIBLE (-5750 6475);
FORCEPROP 2 LAST $SEC 1
J 0
(-5750 6475);
DISPLAY 0.680851 (-5750 6475);
PAINT MONO (-5750 6475);
DISPLAY INVISIBLE (-5750 6475);
FORCEPROP 2 LAST CDS_SEC 1
J 0
(-5750 6475);
DISPLAY 1.021277 (-5750 6475);
DISPLAY INVISIBLE (-5750 6475);
FORCEADD Q_RES..1
(-5700 6450);
FORCEPROP 1 LAST PART_NUMBER CS03322FB03
J 0
(-5800 6525);
DISPLAY 0.404255 (-5800 6525);
DISPLAY INVISIBLE (-5800 6525);
FORCEPROP 1 LAST TOLERANCE 1%
J 0
(-5475 6450);
DISPLAY 0.510638 (-5475 6450);
FORCEPROP 1 LAST VALUE 33.2
J 2
(-5500 6450);
DISPLAY 0.510638 (-5500 6450);
FORCEPROP 1 LAST $LOCATION R894
J 0
(-5900 6450);
DISPLAY 0.638298 (-5900 6450);
FORCEPROP 1 LASTPIN (-5800 6450) $PN 1
J 0
(-5788 6462);
DISPLAY 0.787234 (-5788 6462);
FORCEPROP 1 LASTPIN (-5600 6450) $PN 2
J 0
(-5638 6462);
DISPLAY 0.787234 (-5638 6462);
FORCEPROP 2 LAST CDS_LIB pure_quanta
J 0
(-5700 6450);
PAINT MONO (-5700 6450);
DISPLAY INVISIBLE (-5700 6450);
FORCEPROP 1 LAST MATERIAL CHIP
J 0
(-5800 6550);
DISPLAY 0.404255 (-5800 6550);
DISPLAY INVISIBLE (-5800 6550);
FORCEPROP 1 LAST PACK_TYPE 0402LF
J 0
(-5700 6550);
DISPLAY 0.404255 (-5700 6550);
DISPLAY INVISIBLE (-5700 6550);
FORCEPROP 1 LAST WATTAGE 1/16W
J 2
(-5475 6550);
DISPLAY 0.404255 (-5475 6550);
DISPLAY INVISIBLE (-5475 6550);
FORCEPROP 1 LAST PATH I78
J 0
(-5750 6600);
DISPLAY 0.978723 (-5750 6600);
PAINT WHITE (-5750 6600);
DISPLAY INVISIBLE (-5750 6600);
FORCEPROP 1 LAST $LOCATION R894
J 0
(-5750 6650);
DISPLAY 1.021277 (-5750 6650);
DISPLAY INVISIBLE (-5750 6650);
FORCEPROP 2 LAST CDS_LOCATION R894
J 0
(-5750 6650);
DISPLAY 1.021277 (-5750 6650);
DISPLAY INVISIBLE (-5750 6650);
FORCEPROP 2 LAST $SEC 1
J 0
(-5750 6650);
DISPLAY 0.680851 (-5750 6650);
PAINT MONO (-5750 6650);
DISPLAY INVISIBLE (-5750 6650);
FORCEPROP 2 LAST CDS_SEC 1
J 0
(-5750 6650);
DISPLAY 1.021277 (-5750 6650);
DISPLAY INVISIBLE (-5750 6650);
FORCEADD Q_RES..1
(-5700 6500);
FORCEPROP 1 LAST PART_NUMBER CS03322FB03
J 0
(-5800 6575);
DISPLAY 0.404255 (-5800 6575);
DISPLAY INVISIBLE (-5800 6575);
FORCEPROP 1 LAST TOLERANCE 1%
J 0
(-5475 6500);
DISPLAY 0.510638 (-5475 6500);
FORCEPROP 1 LAST VALUE 33.2
J 2
(-5500 6500);
DISPLAY 0.510638 (-5500 6500);
FORCEPROP 1 LAST PACK_TYPE 0402LF
J 0
(-5700 6600);
DISPLAY 0.404255 (-5700 6600);
FORCEPROP 1 LAST MATERIAL CHIP
J 0
(-5800 6600);
DISPLAY 0.404255 (-5800 6600);
FORCEPROP 1 LAST WATTAGE 1/16W
J 2
(-5475 6600);
DISPLAY 0.404255 (-5475 6600);
FORCEPROP 1 LAST $LOCATION R893
J 0
(-5900 6500);
DISPLAY 0.638298 (-5900 6500);
FORCEPROP 1 LASTPIN (-5800 6500) $PN 1
J 0
(-5788 6512);
DISPLAY 0.787234 (-5788 6512);
FORCEPROP 1 LASTPIN (-5600 6500) $PN 2
J 0
(-5638 6512);
DISPLAY 0.787234 (-5638 6512);
FORCEPROP 2 LAST CDS_LIB pure_quanta
J 0
(-5700 6500);
PAINT MONO (-5700 6500);
DISPLAY INVISIBLE (-5700 6500);
FORCEPROP 1 LAST PATH I79
J 0
(-5750 6650);
DISPLAY 0.978723 (-5750 6650);
PAINT WHITE (-5750 6650);
DISPLAY INVISIBLE (-5750 6650);
FORCEPROP 1 LAST $LOCATION R893
J 0
(-5750 6700);
DISPLAY 1.021277 (-5750 6700);
DISPLAY INVISIBLE (-5750 6700);
FORCEPROP 2 LAST CDS_LOCATION R893
J 0
(-5750 6700);
DISPLAY 1.021277 (-5750 6700);
DISPLAY INVISIBLE (-5750 6700);
FORCEPROP 2 LAST $SEC 1
J 0
(-5750 6700);
DISPLAY 0.680851 (-5750 6700);
PAINT MONO (-5750 6700);
DISPLAY INVISIBLE (-5750 6700);
FORCEPROP 2 LAST CDS_SEC 1
J 0
(-5750 6700);
DISPLAY 1.021277 (-5750 6700);
DISPLAY INVISIBLE (-5750 6700);
FORCEADD OFFPAGE..1
(-10450 5400);
FORCEPROP 2 LAST $XR0 90 
J 0
(-10701 5400);
DISPLAY 0.638298 (-10701 5400);
PAINT MONO (-10701 5400);
FORCEPROP 2 LAST CDS_LIB standard
J 0
(-10450 5400);
PAINT MONO (-10450 5400);
DISPLAY INVISIBLE (-10450 5400);
FORCEPROP 1 LAST OFFPAGE TRUE
J 0
(-10125 5275);
DISPLAY 0.872340 (-10125 5275);
PAINT GREEN (-10125 5275);
DISPLAY INVISIBLE (-10125 5275);
FORCEPROP 1 LAST COMMENT_BODY TRUE
J 0
(-10325 5300);
DISPLAY 0.872340 (-10325 5300);
PAINT GREEN (-10325 5300);
DISPLAY INVISIBLE (-10325 5300);
FORCEPROP 2 LAST PATH I8
J 0
(-10650 5450);
DISPLAY 1.021277 (-10650 5450);
DISPLAY INVISIBLE (-10650 5450);
FORCEADD OFFPAGE..2
(-4625 6500);
FORCEPROP 2 LAST $XR0 115 
J 0
(-4436 6500);
DISPLAY 0.638298 (-4436 6500);
PAINT MONO (-4436 6500);
FORCEPROP 2 LAST CDS_LIB standard
J 0
(-4625 6500);
DISPLAY INVISIBLE (-4625 6500);
FORCEPROP 1 LAST OFFPAGE TRUE
J 0
(-4300 6375);
DISPLAY 0.872340 (-4300 6375);
PAINT GREEN (-4300 6375);
DISPLAY INVISIBLE (-4300 6375);
FORCEPROP 1 LAST COMMENT_BODY TRUE
J 0
(-4670 6405);
DISPLAY 0.872340 (-4670 6405);
PAINT GREEN (-4670 6405);
DISPLAY INVISIBLE (-4670 6405);
FORCEPROP 2 LAST PATH I80
J 0
(-4300 6550);
DISPLAY 1.021277 (-4300 6550);
DISPLAY INVISIBLE (-4300 6550);
FORCEADD OFFPAGE..1
(-10450 5675);
FORCEPROP 2 LAST $XR0 89 
J 0
(-10701 5675);
DISPLAY 0.638298 (-10701 5675);
PAINT MONO (-10701 5675);
FORCEPROP 2 LAST CDS_LIB standard
J 0
(-10450 5675);
PAINT MONO (-10450 5675);
DISPLAY INVISIBLE (-10450 5675);
FORCEPROP 1 LAST OFFPAGE TRUE
J 0
(-10125 5550);
DISPLAY 0.872340 (-10125 5550);
PAINT GREEN (-10125 5550);
DISPLAY INVISIBLE (-10125 5550);
FORCEPROP 1 LAST COMMENT_BODY TRUE
J 0
(-10325 5575);
DISPLAY 0.872340 (-10325 5575);
PAINT GREEN (-10325 5575);
DISPLAY INVISIBLE (-10325 5575);
FORCEPROP 2 LAST PATH I9
J 0
(-10650 5725);
DISPLAY 1.021277 (-10650 5725);
DISPLAY INVISIBLE (-10650 5725);
FORCEADD QUANTA_TITLE_BLOCK_C..1
(-2550 800);
FORCEPROP 0 LAST CDS_CON_LAST_MODIFIED Fri Aug 25 14:01:35 2023
J 0
(-4435 815);
PAINT MONO (-4435 815);
DISPLAY INVISIBLE (-4435 815);
FORCEPROP 2 LAST CUSTOM_TXT_CDS <XR_PAGE_TITLE>
J 0
(-10440 6050);
DISPLAY 0.638298 (-10440 6050);
PAINT PINK (-10440 6050);
DISPLAY INVISIBLE (-10440 6050);
FORCEPROP 2 LAST CUSTOM_TXT_CDS <CON_LAST_MODIFIED>
J 0
(-4435 815);
DISPLAY 0.978723 (-4435 815);
FORCEPROP 2 LAST CUSTOM_TXT_CDS <CON_PAGE_NUM> OF <CON_TOTAL_PAGES>
J 0
(-2996 818);
DISPLAY 0.978723 (-2996 818);
FORCEPROP 2 LAST CUSTOM_TXT_CDS <Q_REV>
J 0
(-2734 903);
DISPLAY 1.212766 (-2734 903);
FORCEPROP 2 LAST CUSTOM_TXT_CDS <Q_PROJ>
J 0
(-4932 902);
DISPLAY 1.212766 (-4932 902);
FORCEPROP 2 LAST CUSTOM_TXT_CDS <Q_NUMBER>
J 0
(-3953 903);
DISPLAY 1.212766 (-3953 903);
FORCEPROP 2 LAST CUSTOM_TXT_CDS <NAME_1>
J 0
(-5725 975);
FORCEPROP 2 LAST CUSTOM_TXT_CDS <NAME_2>
J 0
(-5725 850);
FORCEPROP 1 LAST Q_TITLE DDR5 - PWRGD
J 0
(-11816 801);
DISPLAY 2.446809 (-11816 801);
PAINT GREEN (-11816 801);
FORCEPROP 1 LAST Q_DEPT 
J 1
(-6313 849);
DISPLAY 1.957447 (-6313 849);
PAINT GREEN (-6313 849);
FORCEPROP 2 LAST CDS_XR_PAGE_TITLE CR-114 : @S9S_MB_2U_LIB.S9S_MB_2U(SCH_1):PAGE114
J 0
(-10440 6050);
DISPLAY 0.638298 (-10440 6050);
PAINT PINK (-10440 6050);
DISPLAY INVISIBLE (-10440 6050);
FORCEPROP 2 LAST CDS_LIB pure_quanta
J 0
(-2550 800);
PAINT MONO (-2550 800);
DISPLAY INVISIBLE (-2550 800);
FORCEPROP 1 LAST CDS_LMAN_SYM_OUTLINE -9475,6775,100,-125
J 0
(-2550 800);
DISPLAY 0.468085 (-2550 800);
PAINT GREEN (-2550 800);
DISPLAY INVISIBLE (-2550 800);
FORCEPROP 1 LAST COMMENT_BODY TRUE
J 0
(-2538 787);
DISPLAY 0.978723 (-2538 787);
PAINT GREEN (-2538 787);
DISPLAY INVISIBLE (-2538 787);
FORCEPROP 2 LAST PAGE_BORDER TRUE
J 0
(-10440 6050);
DISPLAY 0.638298 (-10440 6050);
PAINT PINK (-10440 6050);
DISPLAY INVISIBLE (-10440 6050);
WIRE 16 -1 (-10400 5400)(-9475 5400);
FORCEPROP 2 LAST SIG_NAME PWRGD_CHE_CPU0_DIMM1
J 0
(-10325 5410);
DISPLAY 0.680851 (-10325 5410);
PAINT WHITE (-10325 5410);
WIRE 16 -1 (-10400 5125)(-9475 5125);
FORCEPROP 2 LAST SIG_NAME PWRGD_CHF_CPU0_DIMM2
J 0
(-10325 5135);
DISPLAY 0.680851 (-10325 5135);
PAINT WHITE (-10325 5135);
WIRE 16 -1 (-9075 4575)(-9275 4575);
WIRE 16 -1 (-9275 4625)(-9075 4625);
WIRE 16 -1 (-9075 4625)(-9075 4575);
WIRE 16 -1 (-9075 4800)(-9275 4800);
WIRE 16 -1 (-9075 4625)(-9075 4800);
WIRE 16 -1 (-9275 4850)(-9075 4850);
WIRE 16 -1 (-9075 4850)(-9075 4800);
WIRE 16 -1 (-9075 4850)(-8350 4850);
FORCEPROP 2 LAST SIG_NAME PWRGD_FAIL_CPU0_GH
J 0
(-9000 4860);
DISPLAY 0.680851 (-9000 4860);
PAINT WHITE (-9000 4860);
WIRE 16 -1 (-9275 5400)(-9075 5400);
WIRE 16 -1 (-9075 5400)(-8350 5400);
FORCEPROP 2 LAST SIG_NAME PWRGD_FAIL_CPU0_EF
J 0
(-9000 5410);
DISPLAY 0.680851 (-9000 5410);
PAINT WHITE (-9000 5410);
WIRE 16 -1 (-9075 5350)(-9275 5350);
WIRE 16 -1 (-9075 5400)(-9075 5350);
WIRE 16 -1 (-9075 5125)(-9275 5125);
WIRE 16 -1 (-9275 5175)(-9075 5175);
WIRE 16 -1 (-9075 5175)(-9075 5350);
WIRE 16 -1 (-9075 5175)(-9075 5125);
WIRE 16 -1 (-9075 5675)(-9275 5675);
WIRE 16 -1 (-9275 5725)(-9075 5725);
WIRE 16 -1 (-9075 5725)(-9075 5675);
WIRE 16 -1 (-9075 5900)(-9275 5900);
WIRE 16 -1 (-9075 5725)(-9075 5900);
WIRE 16 -1 (-9275 5950)(-9075 5950);
WIRE 16 -1 (-9075 5950)(-9075 5900);
WIRE 16 -1 (-9075 5950)(-8350 5950);
FORCEPROP 2 LAST SIG_NAME PWRGD_FAIL_CPU0_CD
J 0
(-9000 5960);
DISPLAY 0.680851 (-9000 5960);
PAINT WHITE (-9000 5960);
WIRE 16 -1 (-10400 5675)(-9475 5675);
FORCEPROP 2 LAST SIG_NAME PWRGD_CHD_CPU0_DIMM2
J 0
(-10325 5685);
DISPLAY 0.680851 (-10325 5685);
PAINT WHITE (-10325 5685);
WIRE 16 -1 (-10400 5725)(-9475 5725);
FORCEPROP 2 LAST SIG_NAME PWRGD_CHD_CPU0_DIMM1
J 0
(-10325 5735);
DISPLAY 0.680851 (-10325 5735);
PAINT WHITE (-10325 5735);
WIRE 16 -1 (-10400 5950)(-9475 5950);
FORCEPROP 2 LAST SIG_NAME PWRGD_CHC_CPU0_DIMM1
J 0
(-10325 5960);
DISPLAY 0.680851 (-10325 5960);
PAINT WHITE (-10325 5960);
WIRE 16 -1 (-10400 5900)(-9475 5900);
FORCEPROP 2 LAST SIG_NAME PWRGD_CHC_CPU0_DIMM2
J 0
(-10325 5910);
DISPLAY 0.680851 (-10325 5910);
PAINT WHITE (-10325 5910);
WIRE 16 -1 (-5400 4575)(-5600 4575);
WIRE 16 -1 (-5400 4625)(-5400 4575);
WIRE 16 -1 (-5600 4625)(-5400 4625);
WIRE 16 -1 (-5400 4800)(-5600 4800);
WIRE 16 -1 (-5400 4625)(-5400 4800);
WIRE 16 -1 (-5600 4850)(-5400 4850);
WIRE 16 -1 (-5400 4850)(-5400 4800);
WIRE 16 -1 (-5400 4850)(-4675 4850);
FORCEPROP 2 LAST SIG_NAME PWRGD_FAIL_CPU1_GH
J 0
(-5325 4860);
DISPLAY 0.680851 (-5325 4860);
PAINT WHITE (-5325 4860);
WIRE 16 -1 (-5400 5675)(-5600 5675);
WIRE 16 -1 (-5600 5725)(-5400 5725);
WIRE 16 -1 (-5400 5725)(-5400 5675);
WIRE 16 -1 (-5400 5725)(-5400 5900);
WIRE 16 -1 (-5400 5900)(-5600 5900);
WIRE 16 -1 (-5600 5950)(-5400 5950);
WIRE 16 -1 (-5400 5950)(-5400 5900);
WIRE 16 -1 (-5400 5950)(-4675 5950);
FORCEPROP 2 LAST SIG_NAME PWRGD_FAIL_CPU1_CD
J 0
(-5325 5960);
DISPLAY 0.680851 (-5325 5960);
PAINT WHITE (-5325 5960);
WIRE 16 -1 (-5400 6225)(-5600 6225);
WIRE 16 -1 (-5600 6275)(-5400 6275);
WIRE 16 -1 (-5400 6275)(-5400 6225);
WIRE 16 -1 (-5400 6275)(-5400 6450);
WIRE 16 -1 (-5400 6450)(-5600 6450);
WIRE 16 -1 (-5600 6500)(-5400 6500);
WIRE 16 -1 (-5400 6500)(-5400 6450);
WIRE 16 -1 (-5400 6500)(-4675 6500);
FORCEPROP 2 LAST SIG_NAME PWRGD_FAIL_CPU1_AB
J 0
(-5325 6510);
DISPLAY 0.680851 (-5325 6510);
PAINT WHITE (-5325 6510);
WIRE 16 -1 (-5400 5125)(-5600 5125);
WIRE 16 -1 (-5600 5175)(-5400 5175);
WIRE 16 -1 (-5400 5175)(-5400 5125);
WIRE 16 -1 (-5400 5350)(-5600 5350);
WIRE 16 -1 (-5400 5175)(-5400 5350);
WIRE 16 -1 (-5400 5400)(-5400 5350);
WIRE 16 -1 (-5600 5400)(-5400 5400);
WIRE 16 -1 (-5400 5400)(-4675 5400);
FORCEPROP 2 LAST SIG_NAME PWRGD_FAIL_CPU1_EF
J 0
(-5325 5410);
DISPLAY 0.680851 (-5325 5410);
PAINT WHITE (-5325 5410);
WIRE 16 -1 (-6725 5400)(-5800 5400);
FORCEPROP 2 LAST SIG_NAME PWRGD_CHE_CPU1_DIMM1
J 0
(-6650 5410);
DISPLAY 0.680851 (-6650 5410);
PAINT WHITE (-6650 5410);
WIRE 16 -1 (-6725 5675)(-5800 5675);
FORCEPROP 2 LAST SIG_NAME PWRGD_CHD_CPU1_DIMM2
J 0
(-6650 5685);
DISPLAY 0.680851 (-6650 5685);
PAINT WHITE (-6650 5685);
WIRE 16 -1 (-10400 6275)(-9475 6275);
FORCEPROP 2 LAST SIG_NAME PWRGD_CHB_CPU0_DIMM1
J 0
(-10325 6285);
DISPLAY 0.680851 (-10325 6285);
PAINT WHITE (-10325 6285);
WIRE 16 -1 (-10400 6450)(-9475 6450);
FORCEPROP 2 LAST SIG_NAME PWRGD_CHA_CPU0_DIMM2
J 0
(-10325 6460);
DISPLAY 0.680851 (-10325 6460);
PAINT WHITE (-10325 6460);
WIRE 16 -1 (-10400 6500)(-9475 6500);
FORCEPROP 2 LAST SIG_NAME PWRGD_CHA_CPU0_DIMM1
J 0
(-10325 6510);
DISPLAY 0.680851 (-10325 6510);
PAINT WHITE (-10325 6510);
WIRE 16 -1 (-10400 6225)(-9475 6225);
FORCEPROP 2 LAST SIG_NAME PWRGD_CHB_CPU0_DIMM2
J 0
(-10325 6235);
DISPLAY 0.680851 (-10325 6235);
PAINT WHITE (-10325 6235);
WIRE 16 -1 (-9075 6225)(-9275 6225);
WIRE 16 -1 (-9275 6275)(-9075 6275);
WIRE 16 -1 (-9075 6275)(-9075 6225);
WIRE 16 -1 (-9275 6450)(-9075 6450);
WIRE 16 -1 (-9075 6275)(-9075 6450);
WIRE 16 -1 (-9275 6500)(-9075 6500);
WIRE 16 -1 (-9075 6500)(-9075 6450);
WIRE 16 -1 (-9075 6500)(-8350 6500);
FORCEPROP 2 LAST SIG_NAME PWRGD_FAIL_CPU0_AB
J 0
(-9000 6510);
DISPLAY 0.680851 (-9000 6510);
PAINT WHITE (-9000 6510);
WIRE 16 -1 (-6725 6225)(-5800 6225);
FORCEPROP 2 LAST SIG_NAME PWRGD_CHB_CPU1_DIMM2
J 0
(-6650 6235);
DISPLAY 0.680851 (-6650 6235);
PAINT WHITE (-6650 6235);
WIRE 16 -1 (-6725 6275)(-5800 6275);
FORCEPROP 2 LAST SIG_NAME PWRGD_CHB_CPU1_DIMM1
J 0
(-6650 6285);
DISPLAY 0.680851 (-6650 6285);
PAINT WHITE (-6650 6285);
WIRE 16 -1 (-6725 5950)(-5800 5950);
FORCEPROP 2 LAST SIG_NAME PWRGD_CHC_CPU1_DIMM1
J 0
(-6650 5960);
DISPLAY 0.680851 (-6650 5960);
PAINT WHITE (-6650 5960);
WIRE 16 -1 (-6725 5900)(-5800 5900);
FORCEPROP 2 LAST SIG_NAME PWRGD_CHC_CPU1_DIMM2
J 0
(-6650 5910);
DISPLAY 0.680851 (-6650 5910);
PAINT WHITE (-6650 5910);
WIRE 16 -1 (-6725 6500)(-5800 6500);
FORCEPROP 2 LAST SIG_NAME PWRGD_CHA_CPU1_DIMM1
J 0
(-6650 6510);
DISPLAY 0.680851 (-6650 6510);
PAINT WHITE (-6650 6510);
WIRE 16 -1 (-6725 6450)(-5800 6450);
FORCEPROP 2 LAST SIG_NAME PWRGD_CHA_CPU1_DIMM2
J 0
(-6650 6460);
DISPLAY 0.680851 (-6650 6460);
PAINT WHITE (-6650 6460);
WIRE 16 -1 (-6725 5725)(-5800 5725);
FORCEPROP 2 LAST SIG_NAME PWRGD_CHD_CPU1_DIMM1
J 0
(-6650 5735);
DISPLAY 0.680851 (-6650 5735);
PAINT WHITE (-6650 5735);
WIRE 16 -1 (-6725 5350)(-5800 5350);
FORCEPROP 2 LAST SIG_NAME PWRGD_CHE_CPU1_DIMM2
J 0
(-6650 5360);
DISPLAY 0.680851 (-6650 5360);
PAINT WHITE (-6650 5360);
WIRE 16 -1 (-6725 5175)(-5800 5175);
FORCEPROP 2 LAST SIG_NAME PWRGD_CHF_CPU1_DIMM1
J 0
(-6650 5185);
DISPLAY 0.680851 (-6650 5185);
PAINT WHITE (-6650 5185);
WIRE 16 -1 (-6725 5125)(-5800 5125);
FORCEPROP 2 LAST SIG_NAME PWRGD_CHF_CPU1_DIMM2
J 0
(-6650 5135);
DISPLAY 0.680851 (-6650 5135);
PAINT WHITE (-6650 5135);
WIRE 16 -1 (-6725 4850)(-5800 4850);
FORCEPROP 2 LAST SIG_NAME PWRGD_CHG_CPU1_DIMM1
J 0
(-6650 4860);
DISPLAY 0.680851 (-6650 4860);
PAINT WHITE (-6650 4860);
WIRE 16 -1 (-6725 4800)(-5800 4800);
FORCEPROP 2 LAST SIG_NAME PWRGD_CHG_CPU1_DIMM2
J 0
(-6650 4810);
DISPLAY 0.680851 (-6650 4810);
PAINT WHITE (-6650 4810);
WIRE 16 -1 (-6725 4625)(-5800 4625);
FORCEPROP 2 LAST SIG_NAME PWRGD_CHH_CPU1_DIMM1
J 0
(-6650 4635);
DISPLAY 0.680851 (-6650 4635);
PAINT WHITE (-6650 4635);
WIRE 16 -1 (-6725 4575)(-5800 4575);
FORCEPROP 2 LAST SIG_NAME PWRGD_CHH_CPU1_DIMM2
J 0
(-6650 4585);
DISPLAY 0.680851 (-6650 4585);
PAINT WHITE (-6650 4585);
WIRE 16 -1 (-10400 4575)(-9475 4575);
FORCEPROP 2 LAST SIG_NAME PWRGD_CHH_CPU0_DIMM2
J 0
(-10325 4585);
DISPLAY 0.680851 (-10325 4585);
PAINT WHITE (-10325 4585);
WIRE 16 -1 (-10400 5350)(-9475 5350);
FORCEPROP 2 LAST SIG_NAME PWRGD_CHE_CPU0_DIMM2
J 0
(-10325 5360);
DISPLAY 0.680851 (-10325 5360);
PAINT WHITE (-10325 5360);
WIRE 16 -1 (-10400 5175)(-9475 5175);
FORCEPROP 2 LAST SIG_NAME PWRGD_CHF_CPU0_DIMM1
J 0
(-10325 5185);
DISPLAY 0.680851 (-10325 5185);
PAINT WHITE (-10325 5185);
WIRE 16 -1 (-10400 4800)(-9475 4800);
FORCEPROP 2 LAST SIG_NAME PWRGD_CHG_CPU0_DIMM2
J 0
(-10325 4810);
DISPLAY 0.680851 (-10325 4810);
PAINT WHITE (-10325 4810);
WIRE 16 -1 (-10400 4850)(-9475 4850);
FORCEPROP 2 LAST SIG_NAME PWRGD_CHG_CPU0_DIMM1
J 0
(-10325 4860);
DISPLAY 0.680851 (-10325 4860);
PAINT WHITE (-10325 4860);
WIRE 16 -1 (-10400 4625)(-9475 4625);
FORCEPROP 2 LAST SIG_NAME PWRGD_CHH_CPU0_DIMM1
J 0
(-10325 4635);
DISPLAY 0.680851 (-10325 4635);
PAINT WHITE (-10325 4635);
DOT 1 (-9075 5400);
DOT 1 (-5400 6500);
DOT 1 (-9075 6500);
DOT 1 (-9075 5950);
DOT 1 (-9075 4850);
DOT 1 (-9075 6275);
DOT 1 (-9075 6450);
DOT 1 (-9075 5725);
DOT 1 (-9075 5175);
DOT 1 (-9075 5350);
DOT 1 (-9075 4625);
DOT 1 (-9075 4800);
DOT 1 (-5400 4625);
DOT 1 (-5400 4800);
DOT 1 (-5400 4850);
DOT 1 (-5400 5175);
DOT 1 (-5400 5350);
DOT 1 (-5400 5400);
DOT 1 (-5400 5725);
DOT 1 (-5400 5900);
DOT 1 (-5400 5950);
DOT 1 (-5400 6275);
DOT 1 (-5400 6450);
DOT 1 (-9075 5900);
FORCENOTE
20211206 MODIFY FOR GT
(-11825 7225) 0;
DISPLAY LEFT (-11825 7225);
DISPLAY 2.510638 (-11825 7225);
PAINT PINK (-11825 7225);
FORCENOTE
CPU1 DDR
(-6375 6875) 0;
DISPLAY LEFT (-6375 6875);
DISPLAY 4.127660 (-6375 6875);
PAINT WHITE (-6375 6875);
FORCENOTE
CPU0 DDR
(-10050 6875) 0;
DISPLAY LEFT (-10050 6875);
DISPLAY 4.127660 (-10050 6875);
PAINT WHITE (-10050 6875);
QUIT
